FILE_TYPE = MACRO_DRAWING;
SET COLOR_WIRE YELLOW;
SET COLOR_PROP MONO;
SET COLOR_DOT WHITE;
SET COLOR_ARC YELLOW;
SET COLOR_BODY GREEN;
SET COLOR_NOTE MONO;
SET PROP_DISPLAY VALUE;
SET PAGE_NUMBER P71;
FORCEADD PVCCIN_CPU1..1
(-5425 4425);
FORCEPROP 3 LASTPIN (-5425 4375) SIG_NAME PVCCIN_CPU1\g
J 0
(-5415 4385);
DISPLAY 0.659574 (-5415 4385);
PAINT MONO (-5415 4385);
DISPLAY INVISIBLE (-5415 4385);
FORCEPROP 1 LAST VOLTAGE 2.0V
J 0
(-5470 4382);
DISPLAY 0.340426 (-5470 4382);
PAINT SKYBLUE (-5470 4382);
DISPLAY INVISIBLE (-5470 4382);
FORCEPROP 2 LAST CDS_LIB mstr_symbols
J 0
(-5425 4425);
PAINT ORANGE (-5425 4425);
DISPLAY INVISIBLE (-5425 4425);
FORCEPROP 1 LAST BODY_TYPE PLUMBING
J 0
(-5470 4382);
DISPLAY 0.340426 (-5470 4382);
PAINT GREEN (-5470 4382);
DISPLAY INVISIBLE (-5470 4382);
FORCEPROP 1 LAST HDL_POWER PVCCIN_CPU1
J 1
(-5425 4475);
DISPLAY 0.872340 (-5425 4475);
PAINT GREEN (-5425 4475);
DISPLAY INVISIBLE (-5425 4475);
FORCEPROP 1 LAST PATH I35
J 0
(-5375 4450);
DISPLAY 0.872340 (-5375 4450);
PAINT AQUA (-5375 4450);
DISPLAY INVISIBLE (-5375 4450);
FORCEADD PVCCIN_CPU1..1
(-7325 4400);
FORCEPROP 3 LASTPIN (-7325 4350) SIG_NAME PVCCIN_CPU1\g
J 0
(-7315 4360);
DISPLAY 0.659574 (-7315 4360);
PAINT MONO (-7315 4360);
DISPLAY INVISIBLE (-7315 4360);
FORCEPROP 1 LAST VOLTAGE 2.0V
J 0
(-7370 4357);
DISPLAY 0.340426 (-7370 4357);
PAINT SKYBLUE (-7370 4357);
DISPLAY INVISIBLE (-7370 4357);
FORCEPROP 2 LAST CDS_LIB mstr_symbols
J 0
(-7325 4400);
PAINT ORANGE (-7325 4400);
DISPLAY INVISIBLE (-7325 4400);
FORCEPROP 1 LAST BODY_TYPE PLUMBING
J 0
(-7370 4357);
DISPLAY 0.340426 (-7370 4357);
PAINT GREEN (-7370 4357);
DISPLAY INVISIBLE (-7370 4357);
FORCEPROP 1 LAST PATH I36
J 0
(-7275 4425);
DISPLAY 0.872340 (-7275 4425);
PAINT AQUA (-7275 4425);
DISPLAY INVISIBLE (-7275 4425);
FORCEPROP 1 LAST HDL_POWER PVCCIN_CPU1
J 1
(-7325 4450);
DISPLAY 0.872340 (-7325 4450);
PAINT GREEN (-7325 4450);
DISPLAY INVISIBLE (-7325 4450);
FORCEADD OFFPAGE..2
(-875 825);
FORCEPROP 2 LAST $XR0 209 
J 0
(-686 825);
DISPLAY 0.638298 (-686 825);
PAINT MONO (-686 825);
FORCEPROP 1 LAST COMMENT_BODY TRUE
J 0
(-920 730);
DISPLAY 1.170213 (-920 730);
PAINT GREEN (-920 730);
DISPLAY INVISIBLE (-920 730);
FORCEPROP 2 LAST CDS_LIB mstr_standard
J 0
(-875 825);
PAINT ORANGE (-875 825);
DISPLAY INVISIBLE (-875 825);
FORCEPROP 1 LAST OFFPAGE TRUE
J 0
(-550 700);
DISPLAY 1.170213 (-550 700);
PAINT GREEN (-550 700);
DISPLAY INVISIBLE (-550 700);
FORCEPROP 2 LAST PATH I38
J 0
(-700 900);
DISPLAY 1.021277 (-700 900);
PAINT ORANGE (-700 900);
DISPLAY INVISIBLE (-700 900);
FORCEADD OFFPAGE..2
(-875 775);
FORCEPROP 2 LAST $XR0 209 
J 0
(-686 775);
DISPLAY 0.638298 (-686 775);
PAINT MONO (-686 775);
FORCEPROP 1 LAST COMMENT_BODY TRUE
J 0
(-920 680);
DISPLAY 1.170213 (-920 680);
PAINT GREEN (-920 680);
DISPLAY INVISIBLE (-920 680);
FORCEPROP 2 LAST CDS_LIB mstr_standard
J 0
(-875 775);
PAINT ORANGE (-875 775);
DISPLAY INVISIBLE (-875 775);
FORCEPROP 1 LAST OFFPAGE TRUE
J 0
(-550 650);
DISPLAY 1.170213 (-550 650);
PAINT GREEN (-550 650);
DISPLAY INVISIBLE (-550 650);
FORCEPROP 2 LAST PATH I39
J 0
(-700 850);
DISPLAY 1.021277 (-700 850);
PAINT ORANGE (-700 850);
DISPLAY INVISIBLE (-700 850);
FORCEADD PVCCIN_CPU1..1
(-3600 4400);
FORCEPROP 3 LASTPIN (-3600 4350) SIG_NAME PVCCIN_CPU1\g
J 0
(-3590 4360);
DISPLAY 0.659574 (-3590 4360);
PAINT MONO (-3590 4360);
DISPLAY INVISIBLE (-3590 4360);
FORCEPROP 1 LAST VOLTAGE 2.0V
J 0
(-3645 4357);
DISPLAY 0.340426 (-3645 4357);
PAINT SKYBLUE (-3645 4357);
DISPLAY INVISIBLE (-3645 4357);
FORCEPROP 2 LAST CDS_LIB mstr_symbols
J 0
(-3600 4400);
PAINT ORANGE (-3600 4400);
DISPLAY INVISIBLE (-3600 4400);
FORCEPROP 1 LAST BODY_TYPE PLUMBING
J 0
(-3645 4357);
DISPLAY 0.340426 (-3645 4357);
PAINT GREEN (-3645 4357);
DISPLAY INVISIBLE (-3645 4357);
FORCEPROP 1 LAST HDL_POWER PVCCIN_CPU1
J 1
(-3600 4450);
DISPLAY 0.872340 (-3600 4450);
PAINT GREEN (-3600 4450);
DISPLAY INVISIBLE (-3600 4450);
FORCEPROP 1 LAST PATH I40
J 0
(-3550 4425);
DISPLAY 0.872340 (-3550 4425);
PAINT AQUA (-3550 4425);
DISPLAY INVISIBLE (-3550 4425);
FORCEADD PVCCIN_CPU1..1
(-1725 4375);
FORCEPROP 3 LASTPIN (-1725 4325) SIG_NAME PVCCIN_CPU1\g
J 0
(-1715 4335);
DISPLAY 0.659574 (-1715 4335);
PAINT MONO (-1715 4335);
DISPLAY INVISIBLE (-1715 4335);
FORCEPROP 1 LAST VOLTAGE 2.0V
J 0
(-1770 4332);
DISPLAY 0.340426 (-1770 4332);
PAINT SKYBLUE (-1770 4332);
DISPLAY INVISIBLE (-1770 4332);
FORCEPROP 1 LAST BODY_TYPE PLUMBING
J 0
(-1770 4332);
DISPLAY 0.340426 (-1770 4332);
PAINT GREEN (-1770 4332);
DISPLAY INVISIBLE (-1770 4332);
FORCEPROP 2 LAST CDS_LIB mstr_symbols
J 0
(-1725 4375);
PAINT ORANGE (-1725 4375);
DISPLAY INVISIBLE (-1725 4375);
FORCEPROP 1 LAST PATH I41
J 0
(-1675 4400);
DISPLAY 0.872340 (-1675 4400);
PAINT AQUA (-1675 4400);
DISPLAY INVISIBLE (-1675 4400);
FORCEPROP 1 LAST HDL_POWER PVCCIN_CPU1
J 1
(-1725 4425);
DISPLAY 0.872340 (-1725 4425);
PAINT GREEN (-1725 4425);
DISPLAY INVISIBLE (-1725 4425);
FORCEADD GND..1
(-500 525);
FORCEPROP 3 LASTPIN (-500 575) SIG_NAME GND\g
J 0
(-490 585);
DISPLAY 0.659574 (-490 585);
PAINT MONO (-490 585);
DISPLAY INVISIBLE (-490 585);
FORCEPROP 1 LAST BODY_TYPE PLUMBING
J 0
(-545 482);
DISPLAY 0.340426 (-545 482);
PAINT GREEN (-545 482);
DISPLAY INVISIBLE (-545 482);
FORCEPROP 1 LAST VOLTAGE 0.0V
J 0
(-545 482);
DISPLAY 0.340426 (-545 482);
PAINT SKYBLUE (-545 482);
DISPLAY INVISIBLE (-545 482);
FORCEPROP 1 LAST SIZE 1B
J 0
(-425 475);
DISPLAY 1.170213 (-425 475);
PAINT AQUA (-425 475);
DISPLAY INVISIBLE (-425 475);
FORCEPROP 2 LAST CDS_LIB mstr_symbols
J 0
(-500 525);
PAINT ORANGE (-500 525);
DISPLAY INVISIBLE (-500 525);
FORCEPROP 1 LAST PATH I42
J 0
(-425 525);
DISPLAY 0.872340 (-425 525);
PAINT AQUA (-425 525);
DISPLAY INVISIBLE (-425 525);
FORCEPROP 1 LAST HDL_POWER GND
J 0
(-500 675);
DISPLAY 1.170213 (-500 675);
PAINT GREEN (-500 675);
DISPLAY INVISIBLE (-500 675);
FORCEADD RES..2
(-500 750);
FORCEPROP 1 LASTPIN (-500 650) $PN 2
J 0
(-495 660);
DISPLAY 0.617021 (-495 660);
PAINT ORANGE (-495 660);
FORCEPROP 1 LAST PACK_TYPE 0402
J 0
(-460 575);
DISPLAY 0.617021 (-460 575);
PAINT SKYBLUE (-460 575);
FORCEPROP 1 LAST MATERIAL CHIP
J 0
(-460 675);
DISPLAY 0.617021 (-460 675);
PAINT SKYBLUE (-460 675);
FORCEPROP 1 LAST WATTAGE 1/16W
J 0
(-460 725);
DISPLAY 0.617021 (-460 725);
PAINT SKYBLUE (-460 725);
FORCEPROP 1 LASTPIN (-500 850) $PN 1
J 0
(-495 812);
DISPLAY 0.617021 (-495 812);
PAINT ORANGE (-495 812);
FORCEPROP 1 LAST LOCATION R3D27
J 0
(-455 875);
DISPLAY 0.617021 (-455 875);
PAINT AQUA (-455 875);
FORCEPROP 1 LAST VALUE 249
J 0
(-455 825);
DISPLAY 0.617021 (-455 825);
PAINT SKYBLUE (-455 825);
FORCEPROP 1 LAST TOLERANCE 0.1%
J 0
(-455 775);
DISPLAY 0.617021 (-455 775);
PAINT SKYBLUE (-455 775);
FORCEPROP 1 LAST PART_NUMBER G85996-031
J 0
(-460 625);
DISPLAY 0.617021 (-460 625);
PAINT BLUE (-460 625);
FORCEPROP 2 LAST CDS_LIB mstr_discrete
J 0
(-500 750);
PAINT ORANGE (-500 750);
DISPLAY INVISIBLE (-500 750);
FORCEPROP 2 LAST CDS_LOCATION R3D27
J 0
(-455 875);
DISPLAY 0.617021 (-455 875);
PAINT AQUA (-455 875);
DISPLAY INVISIBLE (-455 875);
FORCEPROP 2 LAST ROOM CPU1
J 0
(-450 925);
PAINT MONO (-450 925);
DISPLAY INVISIBLE (-450 925);
FORCEPROP 1 LAST PATH I43
J 0
(-450 925);
DISPLAY 0.978723 (-450 925);
PAINT WHITE (-450 925);
DISPLAY INVISIBLE (-450 925);
FORCEPROP 2 LAST SEC 1
J 0
(-450 975);
DISPLAY 0.680851 (-450 975);
PAINT MONO (-450 975);
DISPLAY INVISIBLE (-450 975);
FORCEPROP 2 LAST BOM_COST PROC_SOCKET
J 0
(-450 975);
PAINT MONO (-450 975);
DISPLAY INVISIBLE (-450 975);
FORCEPROP 2 LAST SEC_TYPE 0402
J 0
(-450 975);
DISPLAY 1.021277 (-450 975);
PAINT ORANGE (-450 975);
DISPLAY INVISIBLE (-450 975);
FORCEADD PVCCIN_CPU1..1
(-1100 1700);
FORCEPROP 3 LASTPIN (-1100 1650) SIG_NAME PVCCIN_CPU1\g
J 0
(-1090 1660);
DISPLAY 0.659574 (-1090 1660);
PAINT MONO (-1090 1660);
DISPLAY INVISIBLE (-1090 1660);
FORCEPROP 1 LAST HDL_POWER PVCCIN_CPU1
J 1
(-1100 1750);
DISPLAY 0.872340 (-1100 1750);
PAINT GREEN (-1100 1750);
DISPLAY INVISIBLE (-1100 1750);
FORCEPROP 1 LAST PATH I45
J 0
(-1050 1725);
DISPLAY 0.872340 (-1050 1725);
PAINT AQUA (-1050 1725);
DISPLAY INVISIBLE (-1050 1725);
FORCEPROP 1 LAST BODY_TYPE PLUMBING
J 0
(-1145 1657);
DISPLAY 0.340426 (-1145 1657);
PAINT GREEN (-1145 1657);
DISPLAY INVISIBLE (-1145 1657);
FORCEPROP 2 LAST CDS_LIB mstr_symbols
J 0
(-1100 1700);
PAINT ORANGE (-1100 1700);
DISPLAY INVISIBLE (-1100 1700);
FORCEPROP 1 LAST VOLTAGE 2.0V
J 0
(-1145 1657);
DISPLAY 0.340426 (-1145 1657);
PAINT SKYBLUE (-1145 1657);
DISPLAY INVISIBLE (-1145 1657);
FORCEADD RES..2
(-1100 1400);
FORCEPROP 1 LASTPIN (-1100 1300) $PN 2
J 0
(-1095 1310);
DISPLAY 0.617021 (-1095 1310);
PAINT ORANGE (-1095 1310);
FORCEPROP 1 LASTPIN (-1100 1500) $PN 1
J 0
(-1095 1462);
DISPLAY 0.617021 (-1095 1462);
PAINT ORANGE (-1095 1462);
FORCEPROP 1 LAST WATTAGE 1/10W
J 0
(-1060 1375);
DISPLAY 0.617021 (-1060 1375);
PAINT SKYBLUE (-1060 1375);
FORCEPROP 1 LAST MATERIAL CHIP
J 0
(-1060 1325);
DISPLAY 0.617021 (-1060 1325);
PAINT SKYBLUE (-1060 1325);
FORCEPROP 1 LAST PACK_TYPE 0603
J 0
(-1060 1225);
DISPLAY 0.617021 (-1060 1225);
PAINT SKYBLUE (-1060 1225);
FORCEPROP 1 LAST TOLERANCE 1%
J 0
(-1055 1425);
DISPLAY 0.617021 (-1055 1425);
PAINT SKYBLUE (-1055 1425);
FORCEPROP 1 LAST VALUE 100.0K
J 0
(-1055 1475);
DISPLAY 0.617021 (-1055 1475);
PAINT SKYBLUE (-1055 1475);
FORCEPROP 1 LAST PART_NUMBER G22026-050
J 0
(-1060 1275);
DISPLAY 0.617021 (-1060 1275);
PAINT BLUE (-1060 1275);
FORCEPROP 1 LAST LOCATION RT8P1
J 0
(-1050 1525);
DISPLAY 0.617021 (-1050 1525);
PAINT AQUA (-1050 1525);
FORCEPROP 2 LAST CDS_LIB mstr_discrete
J 0
(-1100 1400);
PAINT ORANGE (-1100 1400);
DISPLAY INVISIBLE (-1100 1400);
FORCEPROP 2 LAST ROOM CPU1
J 0
(-1025 1500);
PAINT MONO (-1025 1500);
DISPLAY INVISIBLE (-1025 1500);
FORCEPROP 2 LAST CDS_LOCATION RT8P1
J 0
(-1050 1525);
DISPLAY 0.617021 (-1050 1525);
PAINT AQUA (-1050 1525);
DISPLAY INVISIBLE (-1050 1525);
FORCEPROP 1 LAST PATH I49
J 0
(-1050 1575);
DISPLAY 0.978723 (-1050 1575);
PAINT WHITE (-1050 1575);
DISPLAY INVISIBLE (-1050 1575);
FORCEPROP 2 LAST SEC 1
J 0
(-1050 1625);
DISPLAY 0.680851 (-1050 1625);
PAINT MONO (-1050 1625);
DISPLAY INVISIBLE (-1050 1625);
FORCEPROP 2 LAST SEC_TYPE 0603
J 0
(-1050 1625);
DISPLAY 1.021277 (-1050 1625);
PAINT ORANGE (-1050 1625);
DISPLAY INVISIBLE (-1050 1625);
FORCEPROP 2 LAST BOM_COST PROC_SOCKET
J 0
(-1025 1550);
PAINT MONO (-1025 1550);
DISPLAY INVISIBLE (-1025 1550);
FORCEADD SKX_EXT_B..18
(-6375 2525);
FORCEPROP 2 LASTPIN (-7075 825) $PN BF85
J 2
(-7085 835);
DISPLAY 0.617021 (-7085 835);
PAINT ORANGE (-7085 835);
FORCEPROP 2 LASTPIN (-7075 875) $PN BF83
J 2
(-7085 885);
DISPLAY 0.617021 (-7085 885);
PAINT ORANGE (-7085 885);
FORCEPROP 2 LASTPIN (-7075 925) $PN BF81
J 2
(-7085 935);
DISPLAY 0.617021 (-7085 935);
PAINT ORANGE (-7085 935);
FORCEPROP 2 LASTPIN (-7075 975) $PN BF79
J 2
(-7085 985);
DISPLAY 0.617021 (-7085 985);
PAINT ORANGE (-7085 985);
FORCEPROP 2 LASTPIN (-7075 1025) $PN BF77
J 2
(-7085 1035);
DISPLAY 0.617021 (-7085 1035);
PAINT ORANGE (-7085 1035);
FORCEPROP 2 LASTPIN (-7075 1075) $PN BF75
J 2
(-7085 1085);
DISPLAY 0.617021 (-7085 1085);
PAINT ORANGE (-7085 1085);
FORCEPROP 2 LASTPIN (-7075 1125) $PN BF73
J 2
(-7085 1135);
DISPLAY 0.617021 (-7085 1135);
PAINT ORANGE (-7085 1135);
FORCEPROP 2 LASTPIN (-7075 1175) $PN BF61
J 2
(-7085 1185);
DISPLAY 0.617021 (-7085 1185);
PAINT ORANGE (-7085 1185);
FORCEPROP 2 LASTPIN (-7075 1225) $PN BE84
J 2
(-7085 1235);
DISPLAY 0.617021 (-7085 1235);
PAINT ORANGE (-7085 1235);
FORCEPROP 2 LASTPIN (-7075 1275) $PN BE82
J 2
(-7085 1285);
DISPLAY 0.617021 (-7085 1285);
PAINT ORANGE (-7085 1285);
FORCEPROP 2 LASTPIN (-7075 1325) $PN BE80
J 2
(-7085 1335);
DISPLAY 0.617021 (-7085 1335);
PAINT ORANGE (-7085 1335);
FORCEPROP 2 LASTPIN (-7075 1375) $PN BE78
J 2
(-7085 1385);
DISPLAY 0.617021 (-7085 1385);
PAINT ORANGE (-7085 1385);
FORCEPROP 2 LASTPIN (-7075 1425) $PN BE76
J 2
(-7085 1435);
DISPLAY 0.617021 (-7085 1435);
PAINT ORANGE (-7085 1435);
FORCEPROP 2 LASTPIN (-7075 1475) $PN BE74
J 2
(-7085 1485);
DISPLAY 0.617021 (-7085 1485);
PAINT ORANGE (-7085 1485);
FORCEPROP 2 LASTPIN (-7075 1525) $PN BE72
J 2
(-7085 1535);
DISPLAY 0.617021 (-7085 1535);
PAINT ORANGE (-7085 1535);
FORCEPROP 2 LASTPIN (-7075 1575) $PN BE62
J 2
(-7085 1585);
DISPLAY 0.617021 (-7085 1585);
PAINT ORANGE (-7085 1585);
FORCEPROP 2 LASTPIN (-7075 1625) $PN BE60
J 2
(-7085 1635);
DISPLAY 0.617021 (-7085 1635);
PAINT ORANGE (-7085 1635);
FORCEPROP 2 LASTPIN (-7075 1675) $PN BD85
J 2
(-7085 1685);
DISPLAY 0.617021 (-7085 1685);
PAINT ORANGE (-7085 1685);
FORCEPROP 2 LASTPIN (-7075 1725) $PN BD83
J 2
(-7085 1735);
DISPLAY 0.617021 (-7085 1735);
PAINT ORANGE (-7085 1735);
FORCEPROP 2 LASTPIN (-7075 1775) $PN BD81
J 2
(-7085 1785);
DISPLAY 0.617021 (-7085 1785);
PAINT ORANGE (-7085 1785);
FORCEPROP 2 LASTPIN (-7075 1825) $PN BD79
J 2
(-7085 1835);
DISPLAY 0.617021 (-7085 1835);
PAINT ORANGE (-7085 1835);
FORCEPROP 2 LASTPIN (-7075 1875) $PN BD77
J 2
(-7085 1885);
DISPLAY 0.617021 (-7085 1885);
PAINT ORANGE (-7085 1885);
FORCEPROP 2 LASTPIN (-7075 1925) $PN BD75
J 2
(-7085 1935);
DISPLAY 0.617021 (-7085 1935);
PAINT ORANGE (-7085 1935);
FORCEPROP 2 LASTPIN (-7075 1975) $PN BD73
J 2
(-7085 1985);
DISPLAY 0.617021 (-7085 1985);
PAINT ORANGE (-7085 1985);
FORCEPROP 1 LAST PART_NUMBER TBD
J 0
(-7025 625);
DISPLAY 0.617021 (-7025 625);
PAINT BLUE (-7025 625);
FORCEPROP 2 LASTPIN (-7075 2025) $PN BD61
J 2
(-7085 2035);
DISPLAY 0.617021 (-7085 2035);
PAINT ORANGE (-7085 2035);
FORCEPROP 2 LASTPIN (-7075 2075) $PN BC84
J 2
(-7085 2085);
DISPLAY 0.617021 (-7085 2085);
PAINT ORANGE (-7085 2085);
FORCEPROP 2 LASTPIN (-7075 2125) $PN BC62
J 2
(-7085 2135);
DISPLAY 0.617021 (-7085 2135);
PAINT ORANGE (-7085 2135);
FORCEPROP 2 LASTPIN (-7075 2175) $PN BC60
J 2
(-7085 2185);
DISPLAY 0.617021 (-7085 2185);
PAINT ORANGE (-7085 2185);
FORCEPROP 2 LASTPIN (-7075 2225) $PN BB85
J 2
(-7085 2235);
DISPLAY 0.617021 (-7085 2235);
PAINT ORANGE (-7085 2235);
FORCEPROP 2 LASTPIN (-7075 2275) $PN BB61
J 2
(-7085 2285);
DISPLAY 0.617021 (-7085 2285);
PAINT ORANGE (-7085 2285);
FORCEPROP 2 LASTPIN (-7075 2325) $PN BA60
J 2
(-7085 2335);
DISPLAY 0.617021 (-7085 2335);
PAINT ORANGE (-7085 2335);
FORCEPROP 2 LASTPIN (-7075 2375) $PN AY61
J 2
(-7085 2385);
DISPLAY 0.617021 (-7085 2385);
PAINT ORANGE (-7085 2385);
FORCEPROP 2 LASTPIN (-7075 2425) $PN AW60
J 2
(-7085 2435);
DISPLAY 0.617021 (-7085 2435);
PAINT ORANGE (-7085 2435);
FORCEPROP 2 LASTPIN (-7075 2475) $PN AV61
J 2
(-7085 2485);
DISPLAY 0.617021 (-7085 2485);
PAINT ORANGE (-7085 2485);
FORCEPROP 2 LASTPIN (-7075 2525) $PN AV59
J 2
(-7085 2535);
DISPLAY 0.617021 (-7085 2535);
PAINT ORANGE (-7085 2535);
FORCEPROP 2 LASTPIN (-7075 2575) $PN AU60
J 2
(-7085 2585);
DISPLAY 0.617021 (-7085 2585);
PAINT ORANGE (-7085 2585);
FORCEPROP 2 LASTPIN (-7075 2625) $PN AU58
J 2
(-7085 2635);
DISPLAY 0.617021 (-7085 2635);
PAINT ORANGE (-7085 2635);
FORCEPROP 2 LASTPIN (-7075 2675) $PN AT59
J 2
(-7085 2685);
DISPLAY 0.617021 (-7085 2685);
PAINT ORANGE (-7085 2685);
FORCEPROP 2 LASTPIN (-7075 2725) $PN AT57
J 2
(-7085 2735);
DISPLAY 0.617021 (-7085 2735);
PAINT ORANGE (-7085 2735);
FORCEPROP 2 LASTPIN (-7075 2775) $PN AR58
J 2
(-7085 2785);
DISPLAY 0.617021 (-7085 2785);
PAINT ORANGE (-7085 2785);
FORCEPROP 2 LASTPIN (-7075 2825) $PN AR56
J 2
(-7085 2835);
DISPLAY 0.617021 (-7085 2835);
PAINT ORANGE (-7085 2835);
FORCEPROP 2 LASTPIN (-7075 2875) $PN AP57
J 2
(-7085 2885);
DISPLAY 0.617021 (-7085 2885);
PAINT ORANGE (-7085 2885);
FORCEPROP 2 LASTPIN (-7075 2925) $PN AP55
J 2
(-7085 2935);
DISPLAY 0.617021 (-7085 2935);
PAINT ORANGE (-7085 2935);
FORCEPROP 2 LASTPIN (-7075 2975) $PN AN56
J 2
(-7085 2985);
DISPLAY 0.617021 (-7085 2985);
PAINT ORANGE (-7085 2985);
FORCEPROP 2 LASTPIN (-7075 3025) $PN AN54
J 2
(-7085 3035);
DISPLAY 0.617021 (-7085 3035);
PAINT ORANGE (-7085 3035);
FORCEPROP 2 LASTPIN (-7075 3075) $PN AN32
J 2
(-7085 3085);
DISPLAY 0.617021 (-7085 3085);
PAINT ORANGE (-7085 3085);
FORCEPROP 2 LASTPIN (-7075 3125) $PN AM55
J 2
(-7085 3135);
DISPLAY 0.617021 (-7085 3135);
PAINT ORANGE (-7085 3135);
FORCEPROP 2 LASTPIN (-7075 3175) $PN AM53
J 2
(-7085 3185);
DISPLAY 0.617021 (-7085 3185);
PAINT ORANGE (-7085 3185);
FORCEPROP 2 LASTPIN (-7075 3225) $PN AM33
J 2
(-7085 3235);
DISPLAY 0.617021 (-7085 3235);
PAINT ORANGE (-7085 3235);
FORCEPROP 2 LASTPIN (-7075 3275) $PN AL54
J 2
(-7085 3285);
DISPLAY 0.617021 (-7085 3285);
PAINT ORANGE (-7085 3285);
FORCEPROP 2 LASTPIN (-7075 3325) $PN AL52
J 2
(-7085 3335);
DISPLAY 0.617021 (-7085 3335);
PAINT ORANGE (-7085 3335);
FORCEPROP 2 LASTPIN (-7075 3375) $PN AL50
J 2
(-7085 3385);
DISPLAY 0.617021 (-7085 3385);
PAINT ORANGE (-7085 3385);
FORCEPROP 2 LASTPIN (-7075 3425) $PN AL48
J 2
(-7085 3435);
DISPLAY 0.617021 (-7085 3435);
PAINT ORANGE (-7085 3435);
FORCEPROP 2 LASTPIN (-7075 3475) $PN AL46
J 2
(-7085 3485);
DISPLAY 0.617021 (-7085 3485);
PAINT ORANGE (-7085 3485);
FORCEPROP 2 LASTPIN (-7075 3525) $PN AL34
J 2
(-7085 3535);
DISPLAY 0.617021 (-7085 3535);
PAINT ORANGE (-7085 3535);
FORCEPROP 2 LASTPIN (-7075 3575) $PN AK53
J 2
(-7085 3585);
DISPLAY 0.617021 (-7085 3585);
PAINT ORANGE (-7085 3585);
FORCEPROP 2 LASTPIN (-7075 3625) $PN AK51
J 2
(-7085 3635);
DISPLAY 0.617021 (-7085 3635);
PAINT ORANGE (-7085 3635);
FORCEPROP 2 LASTPIN (-7075 3675) $PN AK49
J 2
(-7085 3685);
DISPLAY 0.617021 (-7085 3685);
PAINT ORANGE (-7085 3685);
FORCEPROP 2 LASTPIN (-7075 3725) $PN AK47
J 2
(-7085 3735);
DISPLAY 0.617021 (-7085 3735);
PAINT ORANGE (-7085 3735);
FORCEPROP 2 LASTPIN (-7075 3775) $PN AK45
J 2
(-7085 3785);
DISPLAY 0.617021 (-7085 3785);
PAINT ORANGE (-7085 3785);
FORCEPROP 2 LASTPIN (-7075 3825) $PN AK35
J 2
(-7085 3835);
DISPLAY 0.617021 (-7085 3835);
PAINT ORANGE (-7085 3835);
FORCEPROP 2 LASTPIN (-7075 3875) $PN AJ36
J 2
(-7085 3885);
DISPLAY 0.617021 (-7085 3885);
PAINT ORANGE (-7085 3885);
FORCEPROP 2 LASTPIN (-7075 3925) $PN AH41
J 2
(-7085 3935);
DISPLAY 0.617021 (-7085 3935);
PAINT ORANGE (-7085 3935);
FORCEPROP 2 LASTPIN (-7075 3975) $PN AH39
J 2
(-7085 3985);
DISPLAY 0.617021 (-7085 3985);
PAINT ORANGE (-7085 3985);
FORCEPROP 2 LASTPIN (-7075 4025) $PN AH37
J 2
(-7085 4035);
DISPLAY 0.617021 (-7085 4035);
PAINT ORANGE (-7085 4035);
FORCEPROP 2 LASTPIN (-5675 825) $PN BN78
J 0
(-5665 835);
DISPLAY 0.617021 (-5665 835);
PAINT ORANGE (-5665 835);
FORCEPROP 2 LASTPIN (-5675 875) $PN BN76
J 0
(-5665 885);
DISPLAY 0.617021 (-5665 885);
PAINT ORANGE (-5665 885);
FORCEPROP 2 LASTPIN (-5675 925) $PN BN74
J 0
(-5665 935);
DISPLAY 0.617021 (-5665 935);
PAINT ORANGE (-5665 935);
FORCEPROP 2 LASTPIN (-5675 975) $PN BN72
J 0
(-5665 985);
DISPLAY 0.617021 (-5665 985);
PAINT ORANGE (-5665 985);
FORCEPROP 2 LASTPIN (-5675 1025) $PN BN70
J 0
(-5665 1035);
DISPLAY 0.617021 (-5665 1035);
PAINT ORANGE (-5665 1035);
FORCEPROP 2 LASTPIN (-5675 1075) $PN BN68
J 0
(-5665 1085);
DISPLAY 0.617021 (-5665 1085);
PAINT ORANGE (-5665 1085);
FORCEPROP 2 LASTPIN (-5675 1125) $PN BN66
J 0
(-5665 1135);
DISPLAY 0.617021 (-5665 1135);
PAINT ORANGE (-5665 1135);
FORCEPROP 2 LASTPIN (-5675 1175) $PN BN64
J 0
(-5665 1185);
DISPLAY 0.617021 (-5665 1185);
PAINT ORANGE (-5665 1185);
FORCEPROP 2 LASTPIN (-5675 1225) $PN BN62
J 0
(-5665 1235);
DISPLAY 0.617021 (-5665 1235);
PAINT ORANGE (-5665 1235);
FORCEPROP 2 LASTPIN (-5675 1275) $PN BN60
J 0
(-5665 1285);
DISPLAY 0.617021 (-5665 1285);
PAINT ORANGE (-5665 1285);
FORCEPROP 2 LASTPIN (-5675 1325) $PN BM83
J 0
(-5665 1335);
DISPLAY 0.617021 (-5665 1335);
PAINT ORANGE (-5665 1335);
FORCEPROP 2 LASTPIN (-5675 1375) $PN BM81
J 0
(-5665 1385);
DISPLAY 0.617021 (-5665 1385);
PAINT ORANGE (-5665 1385);
FORCEPROP 2 LASTPIN (-5675 1425) $PN BM79
J 0
(-5665 1435);
DISPLAY 0.617021 (-5665 1435);
PAINT ORANGE (-5665 1435);
FORCEPROP 2 LASTPIN (-5675 1475) $PN BM77
J 0
(-5665 1485);
DISPLAY 0.617021 (-5665 1485);
PAINT ORANGE (-5665 1485);
FORCEPROP 2 LASTPIN (-5675 1525) $PN BM75
J 0
(-5665 1535);
DISPLAY 0.617021 (-5665 1535);
PAINT ORANGE (-5665 1535);
FORCEPROP 2 LASTPIN (-5675 1575) $PN BM73
J 0
(-5665 1585);
DISPLAY 0.617021 (-5665 1585);
PAINT ORANGE (-5665 1585);
FORCEPROP 2 LASTPIN (-5675 1625) $PN BM71
J 0
(-5665 1635);
DISPLAY 0.617021 (-5665 1635);
PAINT ORANGE (-5665 1635);
FORCEPROP 2 LASTPIN (-5675 1675) $PN BM69
J 0
(-5665 1685);
DISPLAY 0.617021 (-5665 1685);
PAINT ORANGE (-5665 1685);
FORCEPROP 2 LASTPIN (-5675 1725) $PN BM67
J 0
(-5665 1735);
DISPLAY 0.617021 (-5665 1735);
PAINT ORANGE (-5665 1735);
FORCEPROP 2 LASTPIN (-5675 1775) $PN BM65
J 0
(-5665 1785);
DISPLAY 0.617021 (-5665 1785);
PAINT ORANGE (-5665 1785);
FORCEPROP 2 LASTPIN (-5675 1825) $PN BM63
J 0
(-5665 1835);
DISPLAY 0.617021 (-5665 1835);
PAINT ORANGE (-5665 1835);
FORCEPROP 2 LASTPIN (-5675 1875) $PN BM61
J 0
(-5665 1885);
DISPLAY 0.617021 (-5665 1885);
PAINT ORANGE (-5665 1885);
FORCEPROP 2 LASTPIN (-5675 1925) $PN BL84
J 0
(-5665 1935);
DISPLAY 0.617021 (-5665 1935);
PAINT ORANGE (-5665 1935);
FORCEPROP 2 LASTPIN (-5675 1975) $PN BL62
J 0
(-5665 1985);
DISPLAY 0.617021 (-5665 1985);
PAINT ORANGE (-5665 1985);
FORCEPROP 2 LASTPIN (-5675 2025) $PN BL60
J 0
(-5665 2035);
DISPLAY 0.617021 (-5665 2035);
PAINT ORANGE (-5665 2035);
FORCEPROP 2 LASTPIN (-5675 2075) $PN BK83
J 0
(-5665 2085);
DISPLAY 0.617021 (-5665 2085);
PAINT ORANGE (-5665 2085);
FORCEPROP 2 LASTPIN (-5675 2125) $PN BK81
J 0
(-5665 2135);
DISPLAY 0.617021 (-5665 2135);
PAINT ORANGE (-5665 2135);
FORCEPROP 2 LASTPIN (-5675 2175) $PN BK79
J 0
(-5665 2185);
DISPLAY 0.617021 (-5665 2185);
PAINT ORANGE (-5665 2185);
FORCEPROP 2 LASTPIN (-5675 2225) $PN BK77
J 0
(-5665 2235);
DISPLAY 0.617021 (-5665 2235);
PAINT ORANGE (-5665 2235);
FORCEPROP 2 LASTPIN (-5675 2275) $PN BK75
J 0
(-5665 2285);
DISPLAY 0.617021 (-5665 2285);
PAINT ORANGE (-5665 2285);
FORCEPROP 2 LASTPIN (-5675 2325) $PN BK73
J 0
(-5665 2335);
DISPLAY 0.617021 (-5665 2335);
PAINT ORANGE (-5665 2335);
FORCEPROP 2 LASTPIN (-5675 2375) $PN BK71
J 0
(-5665 2385);
DISPLAY 0.617021 (-5665 2385);
PAINT ORANGE (-5665 2385);
FORCEPROP 2 LASTPIN (-5675 2425) $PN BK69
J 0
(-5665 2435);
DISPLAY 0.617021 (-5665 2435);
PAINT ORANGE (-5665 2435);
FORCEPROP 2 LASTPIN (-5675 2475) $PN BK67
J 0
(-5665 2485);
DISPLAY 0.617021 (-5665 2485);
PAINT ORANGE (-5665 2485);
FORCEPROP 2 LASTPIN (-5675 2525) $PN BK65
J 0
(-5665 2535);
DISPLAY 0.617021 (-5665 2535);
PAINT ORANGE (-5665 2535);
FORCEPROP 2 LASTPIN (-5675 2575) $PN BK63
J 0
(-5665 2585);
DISPLAY 0.617021 (-5665 2585);
PAINT ORANGE (-5665 2585);
FORCEPROP 2 LASTPIN (-5675 2625) $PN BK61
J 0
(-5665 2635);
DISPLAY 0.617021 (-5665 2635);
PAINT ORANGE (-5665 2635);
FORCEPROP 2 LASTPIN (-5675 2675) $PN BJ84
J 0
(-5665 2685);
DISPLAY 0.617021 (-5665 2685);
PAINT ORANGE (-5665 2685);
FORCEPROP 2 LASTPIN (-5675 2725) $PN BJ82
J 0
(-5665 2735);
DISPLAY 0.617021 (-5665 2735);
PAINT ORANGE (-5665 2735);
FORCEPROP 2 LASTPIN (-5675 2775) $PN BJ80
J 0
(-5665 2785);
DISPLAY 0.617021 (-5665 2785);
PAINT ORANGE (-5665 2785);
FORCEPROP 2 LASTPIN (-5675 2825) $PN BJ78
J 0
(-5665 2835);
DISPLAY 0.617021 (-5665 2835);
PAINT ORANGE (-5665 2835);
FORCEPROP 2 LASTPIN (-5675 2875) $PN BJ76
J 0
(-5665 2885);
DISPLAY 0.617021 (-5665 2885);
PAINT ORANGE (-5665 2885);
FORCEPROP 2 LASTPIN (-5675 2925) $PN BJ74
J 0
(-5665 2935);
DISPLAY 0.617021 (-5665 2935);
PAINT ORANGE (-5665 2935);
FORCEPROP 2 LASTPIN (-5675 2975) $PN BJ72
J 0
(-5665 2985);
DISPLAY 0.617021 (-5665 2985);
PAINT ORANGE (-5665 2985);
FORCEPROP 2 LASTPIN (-5675 3025) $PN BJ70
J 0
(-5665 3035);
DISPLAY 0.617021 (-5665 3035);
PAINT ORANGE (-5665 3035);
FORCEPROP 2 LASTPIN (-5675 3075) $PN BJ68
J 0
(-5665 3085);
DISPLAY 0.617021 (-5665 3085);
PAINT ORANGE (-5665 3085);
FORCEPROP 2 LASTPIN (-5675 3125) $PN BJ66
J 0
(-5665 3135);
DISPLAY 0.617021 (-5665 3135);
PAINT ORANGE (-5665 3135);
FORCEPROP 2 LASTPIN (-5675 3175) $PN BJ64
J 0
(-5665 3185);
DISPLAY 0.617021 (-5665 3185);
PAINT ORANGE (-5665 3185);
FORCEPROP 2 LASTPIN (-5675 3225) $PN BJ62
J 0
(-5665 3235);
DISPLAY 0.617021 (-5665 3235);
PAINT ORANGE (-5665 3235);
FORCEPROP 2 LASTPIN (-5675 3275) $PN BJ60
J 0
(-5665 3285);
DISPLAY 0.617021 (-5665 3285);
PAINT ORANGE (-5665 3285);
FORCEPROP 2 LASTPIN (-5675 3325) $PN BH83
J 0
(-5665 3335);
DISPLAY 0.617021 (-5665 3335);
PAINT ORANGE (-5665 3335);
FORCEPROP 2 LASTPIN (-5675 3375) $PN BH81
J 0
(-5665 3385);
DISPLAY 0.617021 (-5665 3385);
PAINT ORANGE (-5665 3385);
FORCEPROP 2 LASTPIN (-5675 3425) $PN BH79
J 0
(-5665 3435);
DISPLAY 0.617021 (-5665 3435);
PAINT ORANGE (-5665 3435);
FORCEPROP 2 LASTPIN (-5675 3475) $PN BH77
J 0
(-5665 3485);
DISPLAY 0.617021 (-5665 3485);
PAINT ORANGE (-5665 3485);
FORCEPROP 2 LASTPIN (-5675 3525) $PN BH75
J 0
(-5665 3535);
DISPLAY 0.617021 (-5665 3535);
PAINT ORANGE (-5665 3535);
FORCEPROP 2 LASTPIN (-5675 3575) $PN BH73
J 0
(-5665 3585);
DISPLAY 0.617021 (-5665 3585);
PAINT ORANGE (-5665 3585);
FORCEPROP 2 LASTPIN (-5675 3625) $PN BH71
J 0
(-5665 3635);
DISPLAY 0.617021 (-5665 3635);
PAINT ORANGE (-5665 3635);
FORCEPROP 2 LASTPIN (-5675 3675) $PN BH69
J 0
(-5665 3685);
DISPLAY 0.617021 (-5665 3685);
PAINT ORANGE (-5665 3685);
FORCEPROP 2 LASTPIN (-5675 3725) $PN BH67
J 0
(-5665 3735);
DISPLAY 0.617021 (-5665 3735);
PAINT ORANGE (-5665 3735);
FORCEPROP 2 LASTPIN (-5675 3775) $PN BH65
J 0
(-5665 3785);
DISPLAY 0.617021 (-5665 3785);
PAINT ORANGE (-5665 3785);
FORCEPROP 2 LASTPIN (-5675 3825) $PN BH63
J 0
(-5665 3835);
DISPLAY 0.617021 (-5665 3835);
PAINT ORANGE (-5665 3835);
FORCEPROP 2 LASTPIN (-5675 3875) $PN BH61
J 0
(-5665 3885);
DISPLAY 0.617021 (-5665 3885);
PAINT ORANGE (-5665 3885);
FORCEPROP 2 LASTPIN (-5675 3925) $PN BG84
J 0
(-5665 3935);
DISPLAY 0.617021 (-5665 3935);
PAINT ORANGE (-5665 3935);
FORCEPROP 2 LASTPIN (-5675 3975) $PN BG70
J 0
(-5665 3985);
DISPLAY 0.617021 (-5665 3985);
PAINT ORANGE (-5665 3985);
FORCEPROP 2 LASTPIN (-5675 4025) $PN BG68
J 0
(-5665 4035);
DISPLAY 0.617021 (-5665 4035);
PAINT ORANGE (-5665 4035);
FORCEPROP 2 LASTPIN (-5675 4075) $PN BG66
J 0
(-5665 4085);
DISPLAY 0.617021 (-5665 4085);
PAINT ORANGE (-5665 4085);
FORCEPROP 2 LASTPIN (-7075 4075) $PN AG42
J 2
(-7085 4085);
DISPLAY 0.617021 (-7085 4085);
PAINT ORANGE (-7085 4085);
FORCEPROP 2 LASTPIN (-7075 4125) $PN AG40
J 2
(-7085 4135);
DISPLAY 0.617021 (-7085 4135);
PAINT ORANGE (-7085 4135);
FORCEPROP 2 LASTPIN (-7075 4175) $PN AG38
J 2
(-7085 4185);
DISPLAY 0.617021 (-7085 4185);
PAINT ORANGE (-7085 4185);
FORCEPROP 2 LASTPIN (-7075 4225) $PN AF43
J 2
(-7085 4235);
DISPLAY 0.617021 (-7085 4235);
PAINT ORANGE (-7085 4235);
FORCEPROP 1 LAST MATERIAL IC
J 0
(-7025 4425);
DISPLAY 0.617021 (-7025 4425);
PAINT SKYBLUE (-7025 4425);
FORCEPROP 1 LAST LOCATION U2D1
J 0
(-7025 4475);
DISPLAY 0.617021 (-7025 4475);
PAINT AQUA (-7025 4475);
FORCEPROP 2 LASTPIN (-5675 4125) $PN BG64
J 0
(-5665 4135);
DISPLAY 0.617021 (-5665 4135);
PAINT ORANGE (-5665 4135);
FORCEPROP 2 LASTPIN (-5675 4175) $PN BG62
J 0
(-5665 4185);
DISPLAY 0.617021 (-5665 4185);
PAINT ORANGE (-5665 4185);
FORCEPROP 2 LASTPIN (-5675 4225) $PN BG60
J 0
(-5665 4235);
DISPLAY 0.617021 (-5665 4235);
PAINT ORANGE (-5665 4235);
FORCEPROP 2 LAST CDS_LIB chpset_lib
J 0
(-6375 2525);
PAINT ORANGE (-6375 2525);
DISPLAY INVISIBLE (-6375 2525);
FORCEPROP 2 LAST CDS_LOCATION U2D1
J 0
(-7025 4475);
DISPLAY 0.617021 (-7025 4475);
PAINT AQUA (-7025 4475);
DISPLAY INVISIBLE (-7025 4475);
FORCEPROP 2 LAST SEC 18
J 0
(-7025 4525);
DISPLAY 0.680851 (-7025 4525);
PAINT MONO (-7025 4525);
DISPLAY INVISIBLE (-7025 4525);
FORCEPROP 2 LAST SEC_TYPE BGA1
J 0
(-7025 4525);
DISPLAY 1.021277 (-7025 4525);
PAINT ORANGE (-7025 4525);
DISPLAY INVISIBLE (-7025 4525);
FORCEPROP 1 LAST PACK_TYPE BGA1
J 0
(-7025 4525);
PAINT SKYBLUE (-7025 4525);
DISPLAY INVISIBLE (-7025 4525);
FORCEPROP 1 LAST PATH I50
J 0
(-6375 4425);
PAINT GREEN (-6375 4425);
DISPLAY INVISIBLE (-6375 4425);
FORCEADD SKX_EXT_B..19
(-2675 2525);
FORCEPROP 2 LASTPIN (-3375 825) $PN BY83
J 2
(-3385 835);
DISPLAY 0.617021 (-3385 835);
PAINT ORANGE (-3385 835);
FORCEPROP 2 LASTPIN (-3375 875) $PN BY81
J 2
(-3385 885);
DISPLAY 0.617021 (-3385 885);
PAINT ORANGE (-3385 885);
FORCEPROP 2 LASTPIN (-3375 925) $PN BY79
J 2
(-3385 935);
DISPLAY 0.617021 (-3385 935);
PAINT ORANGE (-3385 935);
FORCEPROP 2 LASTPIN (-3375 975) $PN BY77
J 2
(-3385 985);
DISPLAY 0.617021 (-3385 985);
PAINT ORANGE (-3385 985);
FORCEPROP 1 LAST PART_NUMBER TBD
J 0
(-3325 575);
DISPLAY 0.617021 (-3325 575);
PAINT BLUE (-3325 575);
FORCEPROP 2 LASTPIN (-3375 1025) $PN BY75
J 2
(-3385 1035);
DISPLAY 0.617021 (-3385 1035);
PAINT ORANGE (-3385 1035);
FORCEPROP 2 LASTPIN (-3375 1075) $PN BY73
J 2
(-3385 1085);
DISPLAY 0.617021 (-3385 1085);
PAINT ORANGE (-3385 1085);
FORCEPROP 2 LASTPIN (-3375 1125) $PN BY61
J 2
(-3385 1135);
DISPLAY 0.617021 (-3385 1135);
PAINT ORANGE (-3385 1135);
FORCEPROP 2 LASTPIN (-3375 1175) $PN BW84
J 2
(-3385 1185);
DISPLAY 0.617021 (-3385 1185);
PAINT ORANGE (-3385 1185);
FORCEPROP 2 LASTPIN (-3375 1225) $PN BW70
J 2
(-3385 1235);
DISPLAY 0.617021 (-3385 1235);
PAINT ORANGE (-3385 1235);
FORCEPROP 2 LASTPIN (-3375 1275) $PN BW68
J 2
(-3385 1285);
DISPLAY 0.617021 (-3385 1285);
PAINT ORANGE (-3385 1285);
FORCEPROP 2 LASTPIN (-3375 1325) $PN BW66
J 2
(-3385 1335);
DISPLAY 0.617021 (-3385 1335);
PAINT ORANGE (-3385 1335);
FORCEPROP 2 LASTPIN (-3375 1375) $PN BW64
J 2
(-3385 1385);
DISPLAY 0.617021 (-3385 1385);
PAINT ORANGE (-3385 1385);
FORCEPROP 2 LASTPIN (-3375 1425) $PN BW62
J 2
(-3385 1435);
DISPLAY 0.617021 (-3385 1435);
PAINT ORANGE (-3385 1435);
FORCEPROP 2 LASTPIN (-3375 1475) $PN BW60
J 2
(-3385 1485);
DISPLAY 0.617021 (-3385 1485);
PAINT ORANGE (-3385 1485);
FORCEPROP 2 LASTPIN (-3375 1525) $PN BV83
J 2
(-3385 1535);
DISPLAY 0.617021 (-3385 1535);
PAINT ORANGE (-3385 1535);
FORCEPROP 2 LASTPIN (-3375 1675) $PN BV77
J 2
(-3385 1685);
DISPLAY 0.617021 (-3385 1685);
PAINT ORANGE (-3385 1685);
FORCEPROP 2 LASTPIN (-3375 1725) $PN BV75
J 2
(-3385 1735);
DISPLAY 0.617021 (-3385 1735);
PAINT ORANGE (-3385 1735);
FORCEPROP 2 LASTPIN (-3375 1575) $PN BV81
J 2
(-3385 1585);
DISPLAY 0.617021 (-3385 1585);
PAINT ORANGE (-3385 1585);
FORCEPROP 2 LASTPIN (-3375 1625) $PN BV79
J 2
(-3385 1635);
DISPLAY 0.617021 (-3385 1635);
PAINT ORANGE (-3385 1635);
FORCEPROP 2 LASTPIN (-3375 1775) $PN BV73
J 2
(-3385 1785);
DISPLAY 0.617021 (-3385 1785);
PAINT ORANGE (-3385 1785);
FORCEPROP 2 LASTPIN (-3375 1875) $PN BV69
J 2
(-3385 1885);
DISPLAY 0.617021 (-3385 1885);
PAINT ORANGE (-3385 1885);
FORCEPROP 2 LASTPIN (-3375 1825) $PN BV71
J 2
(-3385 1835);
DISPLAY 0.617021 (-3385 1835);
PAINT ORANGE (-3385 1835);
FORCEPROP 2 LASTPIN (-3375 1925) $PN BV67
J 2
(-3385 1935);
DISPLAY 0.617021 (-3385 1935);
PAINT ORANGE (-3385 1935);
FORCEPROP 2 LASTPIN (-3375 1975) $PN BV65
J 2
(-3385 1985);
DISPLAY 0.617021 (-3385 1985);
PAINT ORANGE (-3385 1985);
FORCEPROP 2 LASTPIN (-3375 2025) $PN BV63
J 2
(-3385 2035);
DISPLAY 0.617021 (-3385 2035);
PAINT ORANGE (-3385 2035);
FORCEPROP 2 LASTPIN (-3375 2175) $PN BU82
J 2
(-3385 2185);
DISPLAY 0.617021 (-3385 2185);
PAINT ORANGE (-3385 2185);
FORCEPROP 2 LASTPIN (-3375 2225) $PN BU80
J 2
(-3385 2235);
DISPLAY 0.617021 (-3385 2235);
PAINT ORANGE (-3385 2235);
FORCEPROP 2 LASTPIN (-3375 2075) $PN BV61
J 2
(-3385 2085);
DISPLAY 0.617021 (-3385 2085);
PAINT ORANGE (-3385 2085);
FORCEPROP 2 LASTPIN (-3375 2125) $PN BU84
J 2
(-3385 2135);
DISPLAY 0.617021 (-3385 2135);
PAINT ORANGE (-3385 2135);
FORCEPROP 2 LASTPIN (-3375 2275) $PN BU78
J 2
(-3385 2285);
DISPLAY 0.617021 (-3385 2285);
PAINT ORANGE (-3385 2285);
FORCEPROP 2 LASTPIN (-3375 2375) $PN BU74
J 2
(-3385 2385);
DISPLAY 0.617021 (-3385 2385);
PAINT ORANGE (-3385 2385);
FORCEPROP 2 LASTPIN (-3375 2325) $PN BU76
J 2
(-3385 2335);
DISPLAY 0.617021 (-3385 2335);
PAINT ORANGE (-3385 2335);
FORCEPROP 2 LASTPIN (-3375 2425) $PN BU72
J 2
(-3385 2435);
DISPLAY 0.617021 (-3385 2435);
PAINT ORANGE (-3385 2435);
FORCEPROP 2 LASTPIN (-3375 2475) $PN BU70
J 2
(-3385 2485);
DISPLAY 0.617021 (-3385 2485);
PAINT ORANGE (-3385 2485);
FORCEPROP 2 LASTPIN (-3375 2525) $PN BU68
J 2
(-3385 2535);
DISPLAY 0.617021 (-3385 2535);
PAINT ORANGE (-3385 2535);
FORCEPROP 2 LASTPIN (-3375 2725) $PN BU60
J 2
(-3385 2735);
DISPLAY 0.617021 (-3385 2735);
PAINT ORANGE (-3385 2735);
FORCEPROP 2 LASTPIN (-3375 2775) $PN BT83
J 2
(-3385 2785);
DISPLAY 0.617021 (-3385 2785);
PAINT ORANGE (-3385 2785);
FORCEPROP 2 LASTPIN (-3375 2675) $PN BU62
J 2
(-3385 2685);
DISPLAY 0.617021 (-3385 2685);
PAINT ORANGE (-3385 2685);
FORCEPROP 2 LASTPIN (-3375 2575) $PN BU66
J 2
(-3385 2585);
DISPLAY 0.617021 (-3385 2585);
PAINT ORANGE (-3385 2585);
FORCEPROP 2 LASTPIN (-3375 2625) $PN BU64
J 2
(-3385 2635);
DISPLAY 0.617021 (-3385 2635);
PAINT ORANGE (-3385 2635);
FORCEPROP 2 LASTPIN (-3375 2875) $PN BT79
J 2
(-3385 2885);
DISPLAY 0.617021 (-3385 2885);
PAINT ORANGE (-3385 2885);
FORCEPROP 2 LASTPIN (-3375 2825) $PN BT81
J 2
(-3385 2835);
DISPLAY 0.617021 (-3385 2835);
PAINT ORANGE (-3385 2835);
FORCEPROP 2 LASTPIN (-3375 2925) $PN BT77
J 2
(-3385 2935);
DISPLAY 0.617021 (-3385 2935);
PAINT ORANGE (-3385 2935);
FORCEPROP 2 LASTPIN (-3375 2975) $PN BT75
J 2
(-3385 2985);
DISPLAY 0.617021 (-3385 2985);
PAINT ORANGE (-3385 2985);
FORCEPROP 2 LASTPIN (-3375 3025) $PN BT73
J 2
(-3385 3035);
DISPLAY 0.617021 (-3385 3035);
PAINT ORANGE (-3385 3035);
FORCEPROP 2 LASTPIN (-3375 3075) $PN BT71
J 2
(-3385 3085);
DISPLAY 0.617021 (-3385 3085);
PAINT ORANGE (-3385 3085);
FORCEPROP 2 LASTPIN (-3375 3125) $PN BT69
J 2
(-3385 3135);
DISPLAY 0.617021 (-3385 3135);
PAINT ORANGE (-3385 3135);
FORCEPROP 2 LASTPIN (-3375 3175) $PN BT67
J 2
(-3385 3185);
DISPLAY 0.617021 (-3385 3185);
PAINT ORANGE (-3385 3185);
FORCEPROP 2 LASTPIN (-3375 3225) $PN BT65
J 2
(-3385 3235);
DISPLAY 0.617021 (-3385 3235);
PAINT ORANGE (-3385 3235);
FORCEPROP 2 LASTPIN (-3375 3275) $PN BT63
J 2
(-3385 3285);
DISPLAY 0.617021 (-3385 3285);
PAINT ORANGE (-3385 3285);
FORCEPROP 2 LASTPIN (-3375 3325) $PN BT61
J 2
(-3385 3335);
DISPLAY 0.617021 (-3385 3335);
PAINT ORANGE (-3385 3335);
FORCEPROP 2 LASTPIN (-3375 3375) $PN BR84
J 2
(-3385 3385);
DISPLAY 0.617021 (-3385 3385);
PAINT ORANGE (-3385 3385);
FORCEPROP 2 LASTPIN (-3375 3425) $PN BR62
J 2
(-3385 3435);
DISPLAY 0.617021 (-3385 3435);
PAINT ORANGE (-3385 3435);
FORCEPROP 2 LASTPIN (-3375 3475) $PN BR60
J 2
(-3385 3485);
DISPLAY 0.617021 (-3385 3485);
PAINT ORANGE (-3385 3485);
FORCEPROP 2 LASTPIN (-3375 3525) $PN BP83
J 2
(-3385 3535);
DISPLAY 0.617021 (-3385 3535);
PAINT ORANGE (-3385 3535);
FORCEPROP 2 LASTPIN (-3375 3725) $PN BP75
J 2
(-3385 3735);
DISPLAY 0.617021 (-3385 3735);
PAINT ORANGE (-3385 3735);
FORCEPROP 2 LASTPIN (-3375 3775) $PN BP73
J 2
(-3385 3785);
DISPLAY 0.617021 (-3385 3785);
PAINT ORANGE (-3385 3785);
FORCEPROP 2 LASTPIN (-3375 3675) $PN BP77
J 2
(-3385 3685);
DISPLAY 0.617021 (-3385 3685);
PAINT ORANGE (-3385 3685);
FORCEPROP 2 LASTPIN (-3375 3575) $PN BP81
J 2
(-3385 3585);
DISPLAY 0.617021 (-3385 3585);
PAINT ORANGE (-3385 3585);
FORCEPROP 2 LASTPIN (-3375 3625) $PN BP79
J 2
(-3385 3635);
DISPLAY 0.617021 (-3385 3635);
PAINT ORANGE (-3385 3635);
FORCEPROP 2 LASTPIN (-3375 3825) $PN BP71
J 2
(-3385 3835);
DISPLAY 0.617021 (-3385 3835);
PAINT ORANGE (-3385 3835);
FORCEPROP 2 LASTPIN (-3375 3875) $PN BP69
J 2
(-3385 3885);
DISPLAY 0.617021 (-3385 3885);
PAINT ORANGE (-3385 3885);
FORCEPROP 2 LASTPIN (-3375 3925) $PN BP67
J 2
(-3385 3935);
DISPLAY 0.617021 (-3385 3935);
PAINT ORANGE (-3385 3935);
FORCEPROP 2 LASTPIN (-3375 3975) $PN BP65
J 2
(-3385 3985);
DISPLAY 0.617021 (-3385 3985);
PAINT ORANGE (-3385 3985);
FORCEPROP 2 LASTPIN (-3375 4025) $PN BP63
J 2
(-3385 4035);
DISPLAY 0.617021 (-3385 4035);
PAINT ORANGE (-3385 4035);
FORCEPROP 2 LASTPIN (-1975 825) $PN BA86
J 0
(-1965 835);
DISPLAY 0.617021 (-1965 835);
PAINT ORANGE (-1965 835);
FORCEPROP 2 LASTPIN (-1975 925) $PN AD41
J 0
(-1965 935);
DISPLAY 0.617021 (-1965 935);
PAINT ORANGE (-1965 935);
FORCEPROP 2 LASTPIN (-1975 775) $PN AY85
J 0
(-1965 785);
DISPLAY 0.617021 (-1965 785);
PAINT ORANGE (-1965 785);
FORCEPROP 2 LASTPIN (-1975 1225) $PN CY49
J 0
(-1965 1235);
DISPLAY 0.617021 (-1965 1235);
PAINT ORANGE (-1965 1235);
FORCEPROP 2 LASTPIN (-1975 1025) $PN AW86
J 0
(-1965 1035);
DISPLAY 0.617021 (-1965 1035);
PAINT ORANGE (-1965 1035);
FORCEPROP 2 LASTPIN (-1975 1125) $PN AV85
J 0
(-1965 1135);
DISPLAY 0.617021 (-1965 1135);
PAINT ORANGE (-1965 1135);
FORCEPROP 2 LASTPIN (-1975 1475) $PN CV51
J 0
(-1965 1485);
DISPLAY 0.617021 (-1965 1485);
PAINT ORANGE (-1965 1485);
FORCEPROP 2 LASTPIN (-1975 1425) $PN CW46
J 0
(-1965 1435);
DISPLAY 0.617021 (-1965 1435);
PAINT ORANGE (-1965 1435);
FORCEPROP 2 LASTPIN (-1975 1375) $PN CW48
J 0
(-1965 1385);
DISPLAY 0.617021 (-1965 1385);
PAINT ORANGE (-1965 1385);
FORCEPROP 2 LASTPIN (-1975 1325) $PN CW50
J 0
(-1965 1335);
DISPLAY 0.617021 (-1965 1335);
PAINT ORANGE (-1965 1335);
FORCEPROP 2 LASTPIN (-1975 1275) $PN CY47
J 0
(-1965 1285);
DISPLAY 0.617021 (-1965 1285);
PAINT ORANGE (-1965 1285);
FORCEPROP 2 LASTPIN (-1975 1525) $PN CU54
J 0
(-1965 1535);
DISPLAY 0.617021 (-1965 1535);
PAINT ORANGE (-1965 1535);
FORCEPROP 2 LASTPIN (-1975 1725) $PN CU38
J 0
(-1965 1735);
DISPLAY 0.617021 (-1965 1735);
PAINT ORANGE (-1965 1735);
FORCEPROP 2 LASTPIN (-1975 1675) $PN CU40
J 0
(-1965 1685);
DISPLAY 0.617021 (-1965 1685);
PAINT ORANGE (-1965 1685);
FORCEPROP 2 LASTPIN (-1975 1625) $PN CU42
J 0
(-1965 1635);
DISPLAY 0.617021 (-1965 1635);
PAINT ORANGE (-1965 1635);
FORCEPROP 2 LASTPIN (-1975 1575) $PN CU52
J 0
(-1965 1585);
DISPLAY 0.617021 (-1965 1585);
PAINT ORANGE (-1965 1585);
FORCEPROP 2 LASTPIN (-1975 1775) $PN CT55
J 0
(-1965 1785);
DISPLAY 0.617021 (-1965 1785);
PAINT ORANGE (-1965 1785);
FORCEPROP 2 LASTPIN (-1975 1975) $PN CT37
J 0
(-1965 1985);
DISPLAY 0.617021 (-1965 1985);
PAINT ORANGE (-1965 1985);
FORCEPROP 2 LASTPIN (-1975 1925) $PN CT39
J 0
(-1965 1935);
DISPLAY 0.617021 (-1965 1935);
PAINT ORANGE (-1965 1935);
FORCEPROP 2 LASTPIN (-1975 1875) $PN CT41
J 0
(-1965 1885);
DISPLAY 0.617021 (-1965 1885);
PAINT ORANGE (-1965 1885);
FORCEPROP 2 LASTPIN (-1975 1825) $PN CT53
J 0
(-1965 1835);
DISPLAY 0.617021 (-1965 1835);
PAINT ORANGE (-1965 1835);
FORCEPROP 2 LASTPIN (-1975 2025) $PN CR56
J 0
(-1965 2035);
DISPLAY 0.617021 (-1965 2035);
PAINT ORANGE (-1965 2035);
FORCEPROP 2 LASTPIN (-1975 2225) $PN CP55
J 0
(-1965 2235);
DISPLAY 0.617021 (-1965 2235);
PAINT ORANGE (-1965 2235);
FORCEPROP 2 LASTPIN (-1975 2175) $PN CP57
J 0
(-1965 2185);
DISPLAY 0.617021 (-1965 2185);
PAINT ORANGE (-1965 2185);
FORCEPROP 2 LASTPIN (-1975 2125) $PN CR34
J 0
(-1965 2135);
DISPLAY 0.617021 (-1965 2135);
PAINT ORANGE (-1965 2135);
FORCEPROP 2 LASTPIN (-1975 2075) $PN CR54
J 0
(-1965 2085);
DISPLAY 0.617021 (-1965 2085);
PAINT ORANGE (-1965 2085);
FORCEPROP 2 LASTPIN (-1975 2275) $PN CP33
J 0
(-1965 2285);
DISPLAY 0.617021 (-1965 2285);
PAINT ORANGE (-1965 2285);
FORCEPROP 2 LASTPIN (-1975 2475) $PN CM57
J 0
(-1965 2485);
DISPLAY 0.617021 (-1965 2485);
PAINT ORANGE (-1965 2485);
FORCEPROP 2 LASTPIN (-1975 2425) $PN CM59
J 0
(-1965 2435);
DISPLAY 0.617021 (-1965 2435);
PAINT ORANGE (-1965 2435);
FORCEPROP 2 LASTPIN (-1975 2375) $PN CN56
J 0
(-1965 2385);
DISPLAY 0.617021 (-1965 2385);
PAINT ORANGE (-1965 2385);
FORCEPROP 2 LASTPIN (-1975 2325) $PN CN58
J 0
(-1965 2335);
DISPLAY 0.617021 (-1965 2335);
PAINT ORANGE (-1965 2335);
FORCEPROP 2 LASTPIN (-1975 2525) $PN CL60
J 0
(-1965 2535);
DISPLAY 0.617021 (-1965 2535);
PAINT ORANGE (-1965 2535);
FORCEPROP 2 LASTPIN (-1975 2775) $PN CH85
J 0
(-1965 2785);
DISPLAY 0.617021 (-1965 2785);
PAINT ORANGE (-1965 2785);
FORCEPROP 2 LASTPIN (-1975 2725) $PN CJ60
J 0
(-1965 2735);
DISPLAY 0.617021 (-1965 2735);
PAINT ORANGE (-1965 2735);
FORCEPROP 2 LASTPIN (-1975 2675) $PN CK59
J 0
(-1965 2685);
DISPLAY 0.617021 (-1965 2685);
PAINT ORANGE (-1965 2685);
FORCEPROP 2 LASTPIN (-1975 2625) $PN CK61
J 0
(-1965 2635);
DISPLAY 0.617021 (-1965 2635);
PAINT ORANGE (-1965 2635);
FORCEPROP 2 LASTPIN (-1975 2575) $PN CL58
J 0
(-1965 2585);
DISPLAY 0.617021 (-1965 2585);
PAINT ORANGE (-1965 2585);
FORCEPROP 2 LASTPIN (-1975 3025) $PN CF61
J 0
(-1965 3035);
DISPLAY 0.617021 (-1965 3035);
PAINT ORANGE (-1965 3035);
FORCEPROP 2 LASTPIN (-1975 2975) $PN CF85
J 0
(-1965 2985);
DISPLAY 0.617021 (-1965 2985);
PAINT ORANGE (-1965 2985);
FORCEPROP 2 LASTPIN (-1975 2925) $PN CG60
J 0
(-1965 2935);
DISPLAY 0.617021 (-1965 2935);
PAINT ORANGE (-1965 2935);
FORCEPROP 2 LASTPIN (-1975 2875) $PN CG84
J 0
(-1965 2885);
DISPLAY 0.617021 (-1965 2885);
PAINT ORANGE (-1965 2885);
FORCEPROP 2 LASTPIN (-1975 2825) $PN CH61
J 0
(-1965 2835);
DISPLAY 0.617021 (-1965 2835);
PAINT ORANGE (-1965 2835);
FORCEPROP 2 LASTPIN (-1975 3275) $PN CD61
J 0
(-1965 3285);
DISPLAY 0.617021 (-1965 3285);
PAINT ORANGE (-1965 3285);
FORCEPROP 2 LASTPIN (-1975 3225) $PN CD83
J 0
(-1965 3235);
DISPLAY 0.617021 (-1965 3235);
PAINT ORANGE (-1965 3235);
FORCEPROP 2 LASTPIN (-1975 3175) $PN CD85
J 0
(-1965 3185);
DISPLAY 0.617021 (-1965 3185);
PAINT ORANGE (-1965 3185);
FORCEPROP 2 LASTPIN (-1975 3125) $PN CE60
J 0
(-1965 3135);
DISPLAY 0.617021 (-1965 3135);
PAINT ORANGE (-1965 3135);
FORCEPROP 2 LASTPIN (-1975 3075) $PN CE84
J 0
(-1965 3085);
DISPLAY 0.617021 (-1965 3085);
PAINT ORANGE (-1965 3085);
FORCEPROP 2 LASTPIN (-1975 3525) $PN CB81
J 0
(-1965 3535);
DISPLAY 0.617021 (-1965 3535);
PAINT ORANGE (-1965 3535);
FORCEPROP 2 LASTPIN (-1975 3475) $PN CB83
J 0
(-1965 3485);
DISPLAY 0.617021 (-1965 3485);
PAINT ORANGE (-1965 3485);
FORCEPROP 2 LASTPIN (-1975 3425) $PN CC60
J 0
(-1965 3435);
DISPLAY 0.617021 (-1965 3435);
PAINT ORANGE (-1965 3435);
FORCEPROP 2 LASTPIN (-1975 3375) $PN CC62
J 0
(-1965 3385);
DISPLAY 0.617021 (-1965 3385);
PAINT ORANGE (-1965 3385);
FORCEPROP 2 LASTPIN (-1975 3325) $PN CC84
J 0
(-1965 3335);
DISPLAY 0.617021 (-1965 3335);
PAINT ORANGE (-1965 3335);
FORCEPROP 2 LASTPIN (-1975 3775) $PN CB61
J 0
(-1965 3785);
DISPLAY 0.617021 (-1965 3785);
PAINT ORANGE (-1965 3785);
FORCEPROP 2 LASTPIN (-1975 3725) $PN CB73
J 0
(-1965 3735);
DISPLAY 0.617021 (-1965 3735);
PAINT ORANGE (-1965 3735);
FORCEPROP 2 LASTPIN (-1975 3675) $PN CB75
J 0
(-1965 3685);
DISPLAY 0.617021 (-1965 3685);
PAINT ORANGE (-1965 3685);
FORCEPROP 2 LASTPIN (-1975 3625) $PN CB77
J 0
(-1965 3635);
DISPLAY 0.617021 (-1965 3635);
PAINT ORANGE (-1965 3635);
FORCEPROP 2 LASTPIN (-1975 3575) $PN CB79
J 0
(-1965 3585);
DISPLAY 0.617021 (-1965 3585);
PAINT ORANGE (-1965 3585);
FORCEPROP 2 LASTPIN (-1975 3825) $PN CA84
J 0
(-1965 3835);
DISPLAY 0.617021 (-1965 3835);
PAINT ORANGE (-1965 3835);
FORCEPROP 2 LASTPIN (-1975 4025) $PN CA76
J 0
(-1965 4035);
DISPLAY 0.617021 (-1965 4035);
PAINT ORANGE (-1965 4035);
FORCEPROP 2 LASTPIN (-1975 3975) $PN CA78
J 0
(-1965 3985);
DISPLAY 0.617021 (-1965 3985);
PAINT ORANGE (-1965 3985);
FORCEPROP 2 LASTPIN (-1975 3925) $PN CA80
J 0
(-1965 3935);
DISPLAY 0.617021 (-1965 3935);
PAINT ORANGE (-1965 3935);
FORCEPROP 2 LASTPIN (-1975 3875) $PN CA82
J 0
(-1965 3885);
DISPLAY 0.617021 (-1965 3885);
PAINT ORANGE (-1965 3885);
FORCEPROP 2 LASTPIN (-1975 4075) $PN CA74
J 0
(-1965 4085);
DISPLAY 0.617021 (-1965 4085);
PAINT ORANGE (-1965 4085);
FORCEPROP 2 LASTPIN (-3375 4075) $PN BP61
J 2
(-3385 4085);
DISPLAY 0.617021 (-3385 4085);
PAINT ORANGE (-3385 4085);
FORCEPROP 2 LASTPIN (-3375 4125) $PN BN84
J 2
(-3385 4135);
DISPLAY 0.617021 (-3385 4135);
PAINT ORANGE (-3385 4135);
FORCEPROP 2 LASTPIN (-3375 4175) $PN BN82
J 2
(-3385 4185);
DISPLAY 0.617021 (-3385 4185);
PAINT ORANGE (-3385 4185);
FORCEPROP 2 LASTPIN (-3375 4225) $PN BN80
J 2
(-3385 4235);
DISPLAY 0.617021 (-3385 4235);
PAINT ORANGE (-3385 4235);
FORCEPROP 1 LAST MATERIAL IC
J 0
(-3325 4425);
DISPLAY 0.617021 (-3325 4425);
PAINT SKYBLUE (-3325 4425);
FORCEPROP 1 LAST LOCATION U2D1
J 0
(-3325 4475);
DISPLAY 0.617021 (-3325 4475);
PAINT AQUA (-3325 4475);
FORCEPROP 2 LASTPIN (-1975 4125) $PN CA72
J 0
(-1965 4135);
DISPLAY 0.617021 (-1965 4135);
PAINT ORANGE (-1965 4135);
FORCEPROP 2 LASTPIN (-1975 4175) $PN CA62
J 0
(-1965 4185);
DISPLAY 0.617021 (-1965 4185);
PAINT ORANGE (-1965 4185);
FORCEPROP 2 LASTPIN (-1975 4225) $PN CA60
J 0
(-1965 4235);
DISPLAY 0.617021 (-1965 4235);
PAINT ORANGE (-1965 4235);
FORCEPROP 2 LAST CDS_LIB chpset_lib
J 0
(-2675 2525);
PAINT ORANGE (-2675 2525);
DISPLAY INVISIBLE (-2675 2525);
FORCEPROP 2 LAST CDS_LOCATION U2D1
J 0
(-3325 4475);
DISPLAY 0.617021 (-3325 4475);
PAINT AQUA (-3325 4475);
DISPLAY INVISIBLE (-3325 4475);
FORCEPROP 2 LAST SEC 19
J 0
(-3325 4525);
DISPLAY 0.680851 (-3325 4525);
PAINT MONO (-3325 4525);
DISPLAY INVISIBLE (-3325 4525);
FORCEPROP 2 LAST SEC_TYPE BGA1
J 0
(-3325 4525);
DISPLAY 1.021277 (-3325 4525);
PAINT ORANGE (-3325 4525);
DISPLAY INVISIBLE (-3325 4525);
FORCEPROP 1 LAST PACK_TYPE BGA1
J 0
(-3325 4525);
PAINT SKYBLUE (-3325 4525);
DISPLAY INVISIBLE (-3325 4525);
FORCEPROP 1 LAST PATH I51
J 0
(-2675 4425);
PAINT GREEN (-2675 4425);
DISPLAY INVISIBLE (-2675 4425);
FORCEADD PVCCIO_CPU1..1
(-500 1500);
FORCEPROP 3 LASTPIN (-500 1450) SIG_NAME PVCCIO_CPU1\g
J 0
(-490 1460);
DISPLAY 0.659574 (-490 1460);
PAINT MONO (-490 1460);
DISPLAY INVISIBLE (-490 1460);
FORCEPROP 1 LAST BODY_TYPE PLUMBING
J 0
(-545 1457);
DISPLAY 0.340426 (-545 1457);
PAINT GREEN (-545 1457);
DISPLAY INVISIBLE (-545 1457);
FORCEPROP 1 LAST VOLTAGE 1.1V
J 0
(-545 1457);
DISPLAY 0.340426 (-545 1457);
PAINT SKYBLUE (-545 1457);
DISPLAY INVISIBLE (-545 1457);
FORCEPROP 1 LAST PATH I52
J 0
(-450 1525);
DISPLAY 0.872340 (-450 1525);
PAINT AQUA (-450 1525);
DISPLAY INVISIBLE (-450 1525);
FORCEPROP 2 LAST CDS_LIB mstr_symbols
J 0
(-500 1500);
PAINT ORANGE (-500 1500);
DISPLAY INVISIBLE (-500 1500);
FORCEPROP 1 LAST HDL_POWER PVCCIO_CPU1
J 1
(-500 1550);
DISPLAY 0.872340 (-500 1550);
PAINT GREEN (-500 1550);
DISPLAY INVISIBLE (-500 1550);
FORCEADD RES..2
(-500 1200);
FORCEPROP 1 LASTPIN (-500 1100) $PN 2
J 0
(-495 1110);
DISPLAY 0.617021 (-495 1110);
PAINT ORANGE (-495 1110);
FORCEPROP 1 LAST TOLERANCE 1%
J 0
(-455 1225);
DISPLAY 0.617021 (-455 1225);
PAINT SKYBLUE (-455 1225);
FORCEPROP 1 LAST WATTAGE 1/16W
J 0
(-460 1175);
DISPLAY 0.617021 (-460 1175);
PAINT SKYBLUE (-460 1175);
FORCEPROP 1 LAST PACK_TYPE 0402
J 0
(-460 1025);
DISPLAY 0.617021 (-460 1025);
PAINT SKYBLUE (-460 1025);
FORCEPROP 1 LAST MATERIAL EMPTY
J 0
(-460 1125);
DISPLAY 0.617021 (-460 1125);
PAINT RED (-460 1125);
FORCEPROP 1 LASTPIN (-500 1300) $PN 1
J 0
(-495 1262);
DISPLAY 0.617021 (-495 1262);
PAINT ORANGE (-495 1262);
FORCEPROP 1 LAST VALUE 10.0
J 0
(-455 1275);
DISPLAY 0.617021 (-455 1275);
PAINT SKYBLUE (-455 1275);
FORCEPROP 1 LAST LOCATION R3D32
J 0
(-455 1325);
DISPLAY 0.617021 (-455 1325);
PAINT AQUA (-455 1325);
FORCEPROP 1 LAST PART_NUMBER G21796-066
J 0
(-460 1075);
DISPLAY 0.617021 (-460 1075);
PAINT BLUE (-460 1075);
FORCEPROP 2 LAST CDS_LIB mstr_discrete
J 0
(-500 1200);
PAINT ORANGE (-500 1200);
DISPLAY INVISIBLE (-500 1200);
FORCEPROP 1 LAST PATH I53
J 0
(-450 1375);
DISPLAY 0.978723 (-450 1375);
PAINT WHITE (-450 1375);
DISPLAY INVISIBLE (-450 1375);
FORCEPROP 0 LAST ROOM CPU1
J 0
(-450 1425);
DISPLAY 1.021277 (-450 1425);
PAINT ORANGE (-450 1425);
DISPLAY INVISIBLE (-450 1425);
FORCEPROP 2 LAST SEC 1
J 0
(-450 1425);
DISPLAY 0.680851 (-450 1425);
PAINT MONO (-450 1425);
DISPLAY INVISIBLE (-450 1425);
FORCEPROP 2 LAST SEC_TYPE 0402
J 0
(-450 1425);
DISPLAY 1.021277 (-450 1425);
PAINT ORANGE (-450 1425);
DISPLAY INVISIBLE (-450 1425);
FORCEADD PRELIM..10
(-6465 2515);
PAINT GRAY (-6465 2515);
FORCEPROP 1 LAST COMMENT_BODY TRUE
J 0
(-6465 2515);
PAINT ORANGE (-6465 2515);
DISPLAY INVISIBLE (-6465 2515);
FORCEPROP 2 LAST CDS_LIB mstr_misc
J 0
(-6465 2515);
PAINT ORANGE (-6465 2515);
DISPLAY INVISIBLE (-6465 2515);
FORCEADD DESIGN_NOTE..1
(-5175 600);
FORCEPROP 0 LAST L1 CPU SYMBOLS 1-30 ARE PRELIMINARY AND SUBJECT TO CHANGE
J 0
(-5375 475);
DISPLAY 1.021277 (-5375 475);
PAINT ORANGE (-5375 475);
FORCEPROP 1 LAST COMMENT_BODY TRUE
J 0
(-5150 700);
DISPLAY 0.978723 (-5150 700);
PAINT ORANGE (-5150 700);
DISPLAY INVISIBLE (-5150 700);
FORCEPROP 2 LAST CDS_LIB mstr_symbols
J 0
(-5175 600);
PAINT ORANGE (-5175 600);
DISPLAY INVISIBLE (-5175 600);
FORCEADD INTEL_CORP_BPAGE..1
(0 0);
FORCEPROP 1 LAST CDS_CON_LAST_MODIFIED Tue Dec 01 11:51:38 2015
J 0
(-1425 325);
DISPLAY 1.340426 (-1425 325);
PAINT GREEN (-1425 325);
DISPLAY INVISIBLE (-1425 325);
FORCEPROP 1 LAST CUSTOM_TXT_CDS <CURRENT_DESIGN_SHEET> OF <TOTAL_DESIGN_SHEETS>
J 0
(-500 25);
PAINT GREEN (-500 25);
FORCEPROP 1 LAST CUSTOM_TXT_CDS <CON_LAST_MODIFIED>
J 0
(-1925 350);
PAINT GREEN (-1925 350);
FORCEPROP 2 LAST CUSTOM_TXT_CDS <XR_PAGE_TITLE>
J 0
(-7890 5250);
DISPLAY 0.638298 (-7890 5250);
PAINT PINK (-7890 5250);
DISPLAY INVISIBLE (-7890 5250);
FORCEPROP 1 LAST SCH_TITLE SKYLAKE - SKT1 - 17 OF 21
J 0
(-7950 50);
DISPLAY 1.212766 (-7950 50);
PAINT GREEN (-7950 50);
FORCEPROP 1 LAST SCH_ADDRESS1 2200 Mission College Blvd.
J 0
(-3975 125);
DISPLAY 0.617021 (-3975 125);
PAINT GREEN (-3975 125);
FORCEPROP 1 LAST SCH_ADDRESS3 Santa Clara, CA 95052-8119
J 0
(-3975 25);
DISPLAY 0.617021 (-3975 25);
PAINT GREEN (-3975 25);
FORCEPROP 1 LAST SCH_ADDRESS2 P.O. BOX 58119
J 0
(-3975 75);
DISPLAY 0.617021 (-3975 75);
PAINT GREEN (-3975 75);
FORCEPROP 1 LAST SCH_NUMBER H4694802
J 0
(-1300 150);
DISPLAY 1.212766 (-1300 150);
PAINT YELLOW (-1300 150);
FORCEPROP 1 LAST SCH_DEPT BESD
J 1
(-4450 100);
DISPLAY 1.212766 (-4450 100);
PAINT YELLOW (-4450 100);
FORCEPROP 1 LAST SCH_REV 2.420
J 0
(-250 150);
DISPLAY 0.978723 (-250 150);
PAINT YELLOW (-250 150);
FORCEPROP 2 LAST PAGE_BORDER TRUE
J 0
(-7890 5250);
DISPLAY 0.851064 (-7890 5250);
PAINT PINK (-7890 5250);
DISPLAY INVISIBLE (-7890 5250);
FORCEPROP 2 LAST CDS_LIB mstr_symbols
J 0
(0 0);
PAINT ORANGE (0 0);
DISPLAY INVISIBLE (0 0);
FORCEPROP 1 LAST COMMENT_BODY TRUE
J 0
(12 12);
DISPLAY 0.638298 (12 12);
PAINT GREEN (12 12);
DISPLAY INVISIBLE (12 12);
FORCEPROP 2 LAST CDS_XR_PAGE_TITLE CR-71 : @BASEBOARD_FAB2_LIB.BASEBOARD_FAB2(SCH_1):PAGE71
J 0
(-7890 5250);
DISPLAY 0.638298 (-7890 5250);
PAINT PINK (-7890 5250);
DISPLAY INVISIBLE (-7890 5250);
FORCEADD DNS..2
(-495 1195);
PAINT RED (-495 1195);
FORCEPROP 1 LAST COMMENT_BODY TRUE
R 1
J 0
(-420 970);
DISPLAY 0.872340 (-420 970);
PAINT GREEN (-420 970);
DISPLAY INVISIBLE (-420 970);
FORCEPROP 2 LAST CDS_LIB mstr_misc
J 0
(-495 1195);
PAINT ORANGE (-495 1195);
DISPLAY INVISIBLE (-495 1195);
WIRE 16 -1 (-5675 825)(-5425 825);
WIRE 16 -1 (-5425 825)(-5425 875);
WIRE 16 -1 (-5675 875)(-5425 875);
WIRE 16 -1 (-5425 875)(-5425 925);
WIRE 16 -1 (-5675 925)(-5425 925);
WIRE 16 -1 (-5425 975)(-5425 925);
WIRE 16 -1 (-5425 1025)(-5425 975);
WIRE 16 -1 (-5425 975)(-5675 975);
WIRE 16 -1 (-5425 1075)(-5425 1025);
WIRE 16 -1 (-5425 1025)(-5675 1025);
WIRE 16 -1 (-5675 1075)(-5425 1075);
WIRE 16 -1 (-5425 1125)(-5425 1075);
WIRE 16 -1 (-5425 1125)(-5425 1175);
WIRE 16 -1 (-5425 1125)(-5675 1125);
WIRE 16 -1 (-5425 1175)(-5425 1225);
WIRE 16 -1 (-5425 1175)(-5675 1175);
WIRE 16 -1 (-5425 1225)(-5425 1275);
WIRE 16 -1 (-5425 1225)(-5675 1225);
WIRE 16 -1 (-5425 1275)(-5425 1325);
WIRE 16 -1 (-5425 1275)(-5675 1275);
WIRE 16 -1 (-5425 1325)(-5425 1375);
WIRE 16 -1 (-5425 1325)(-5675 1325);
WIRE 16 -1 (-5425 1425)(-5425 1375);
WIRE 16 -1 (-5425 1375)(-5675 1375);
WIRE 16 -1 (-5425 1475)(-5425 1425);
WIRE 16 -1 (-5425 1425)(-5675 1425);
WIRE 16 -1 (-5425 1475)(-5425 1525);
WIRE 16 -1 (-5425 1475)(-5675 1475);
WIRE 16 -1 (-5675 1525)(-5425 1525);
WIRE 16 -1 (-5425 1525)(-5425 1575);
WIRE 16 -1 (-5675 1575)(-5425 1575);
WIRE 16 -1 (-5425 1575)(-5425 1625);
WIRE 16 -1 (-5675 1625)(-5425 1625);
WIRE 16 -1 (-5425 1675)(-5425 1625);
WIRE 16 -1 (-5425 1725)(-5425 1675);
WIRE 16 -1 (-5425 1675)(-5675 1675);
WIRE 16 -1 (-5425 1775)(-5425 1725);
WIRE 16 -1 (-5425 1725)(-5675 1725);
WIRE 16 -1 (-5675 1775)(-5425 1775);
WIRE 16 -1 (-5425 1825)(-5425 1775);
WIRE 16 -1 (-5425 1825)(-5425 1875);
WIRE 16 -1 (-5425 1825)(-5675 1825);
WIRE 16 -1 (-5425 1875)(-5425 1925);
WIRE 16 -1 (-5425 1875)(-5675 1875);
WIRE 16 -1 (-5425 1925)(-5425 1975);
WIRE 16 -1 (-5425 1925)(-5675 1925);
WIRE 16 -1 (-5425 1975)(-5425 2025);
WIRE 16 -1 (-5425 1975)(-5675 1975);
WIRE 16 -1 (-5425 2025)(-5425 2075);
WIRE 16 -1 (-5425 2025)(-5675 2025);
WIRE 16 -1 (-5425 2125)(-5425 2075);
WIRE 16 -1 (-5425 2075)(-5675 2075);
WIRE 16 -1 (-5425 2175)(-5425 2125);
WIRE 16 -1 (-5425 2125)(-5675 2125);
WIRE 16 -1 (-5425 2175)(-5425 2225);
WIRE 16 -1 (-5425 2175)(-5675 2175);
WIRE 16 -1 (-5675 2225)(-5425 2225);
WIRE 16 -1 (-5425 2225)(-5425 2275);
WIRE 16 -1 (-5675 2275)(-5425 2275);
WIRE 16 -1 (-5425 2275)(-5425 2325);
WIRE 16 -1 (-5675 2325)(-5425 2325);
WIRE 16 -1 (-5425 2375)(-5425 2325);
WIRE 16 -1 (-5425 2425)(-5425 2375);
WIRE 16 -1 (-5425 2375)(-5675 2375);
WIRE 16 -1 (-5425 2475)(-5425 2425);
WIRE 16 -1 (-5425 2425)(-5675 2425);
WIRE 16 -1 (-5675 2475)(-5425 2475);
WIRE 16 -1 (-5425 2525)(-5425 2475);
WIRE 16 -1 (-5425 2525)(-5425 2575);
WIRE 16 -1 (-5425 2525)(-5675 2525);
WIRE 16 -1 (-5425 2575)(-5425 2625);
WIRE 16 -1 (-5425 2575)(-5675 2575);
WIRE 16 -1 (-5425 2625)(-5425 2675);
WIRE 16 -1 (-5425 2625)(-5675 2625);
WIRE 16 -1 (-5425 2675)(-5425 2725);
WIRE 16 -1 (-5425 2675)(-5675 2675);
WIRE 16 -1 (-5425 2725)(-5425 2775);
WIRE 16 -1 (-5425 2725)(-5675 2725);
WIRE 16 -1 (-5425 2825)(-5425 2775);
WIRE 16 -1 (-5425 2775)(-5675 2775);
WIRE 16 -1 (-5425 2875)(-5425 2825);
WIRE 16 -1 (-5425 2825)(-5675 2825);
WIRE 16 -1 (-5425 2875)(-5425 2925);
WIRE 16 -1 (-5425 2875)(-5675 2875);
WIRE 16 -1 (-5425 2925)(-5425 2975);
WIRE 16 -1 (-5425 2925)(-5675 2925);
WIRE 16 -1 (-5425 3025)(-5425 2975);
WIRE 16 -1 (-5425 2975)(-5675 2975);
WIRE 16 -1 (-5425 3075)(-5425 3025);
WIRE 16 -1 (-5425 3025)(-5675 3025);
WIRE 16 -1 (-5425 3125)(-5425 3075);
WIRE 16 -1 (-5425 3075)(-5675 3075);
WIRE 16 -1 (-5425 3175)(-5425 3125);
WIRE 16 -1 (-5425 3125)(-5675 3125);
WIRE 16 -1 (-5425 3225)(-5425 3175);
WIRE 16 -1 (-5425 3175)(-5675 3175);
WIRE 16 -1 (-5425 3275)(-5425 3225);
WIRE 16 -1 (-5425 3225)(-5675 3225);
WIRE 16 -1 (-5425 3325)(-5425 3275);
WIRE 16 -1 (-5425 3275)(-5675 3275);
WIRE 16 -1 (-5425 3375)(-5425 3325);
WIRE 16 -1 (-5425 3325)(-5675 3325);
WIRE 16 -1 (-5425 3425)(-5425 3375);
WIRE 16 -1 (-5425 3375)(-5675 3375);
WIRE 16 -1 (-5425 3475)(-5425 3425);
WIRE 16 -1 (-5425 3425)(-5675 3425);
WIRE 16 -1 (-5425 3525)(-5425 3475);
WIRE 16 -1 (-5425 3475)(-5675 3475);
WIRE 16 -1 (-5425 3575)(-5425 3525);
WIRE 16 -1 (-5425 3525)(-5675 3525);
WIRE 16 -1 (-5425 3625)(-5425 3575);
WIRE 16 -1 (-5425 3575)(-5675 3575);
WIRE 16 -1 (-5425 3675)(-5425 3625);
WIRE 16 -1 (-5425 3625)(-5675 3625);
WIRE 16 -1 (-5425 3725)(-5425 3675);
WIRE 16 -1 (-5425 3675)(-5675 3675);
WIRE 16 -1 (-5425 3775)(-5425 3725);
WIRE 16 -1 (-5425 3725)(-5675 3725);
WIRE 16 -1 (-5425 3825)(-5425 3775);
WIRE 16 -1 (-5425 3775)(-5675 3775);
WIRE 16 -1 (-5425 3875)(-5425 3825);
WIRE 16 -1 (-5425 3825)(-5675 3825);
WIRE 16 -1 (-5425 3925)(-5425 3875);
WIRE 16 -1 (-5425 3875)(-5675 3875);
WIRE 16 -1 (-5425 3975)(-5425 3925);
WIRE 16 -1 (-5425 3925)(-5675 3925);
WIRE 16 -1 (-5425 4025)(-5425 3975);
WIRE 16 -1 (-5425 3975)(-5675 3975);
WIRE 16 -1 (-5425 4075)(-5425 4025);
WIRE 16 -1 (-5425 4025)(-5675 4025);
WIRE 16 -1 (-5425 4125)(-5425 4075);
WIRE 16 -1 (-5425 4075)(-5675 4075);
WIRE 16 -1 (-5425 4125)(-5425 4175);
WIRE 16 -1 (-5425 4125)(-5675 4125);
WIRE 16 -1 (-5425 4175)(-5425 4225);
WIRE 16 -1 (-5425 4175)(-5675 4175);
WIRE 16 -1 (-5425 4225)(-5425 4375);
WIRE 16 -1 (-5425 4225)(-5675 4225);
WIRE 16 -1 (-7075 825)(-7325 825);
WIRE 16 -1 (-7325 875)(-7325 825);
WIRE 16 -1 (-7075 875)(-7325 875);
WIRE 16 -1 (-7325 925)(-7325 875);
WIRE 16 -1 (-7075 925)(-7325 925);
WIRE 16 -1 (-7325 975)(-7325 925);
WIRE 16 -1 (-7075 975)(-7325 975);
WIRE 16 -1 (-7325 1025)(-7325 975);
WIRE 16 -1 (-7075 1025)(-7325 1025);
WIRE 16 -1 (-7325 1075)(-7325 1025);
WIRE 16 -1 (-7075 1075)(-7325 1075);
WIRE 16 -1 (-7325 1125)(-7325 1075);
WIRE 16 -1 (-7075 1125)(-7325 1125);
WIRE 16 -1 (-7325 1175)(-7325 1125);
WIRE 16 -1 (-7075 1175)(-7325 1175);
WIRE 16 -1 (-7325 1225)(-7325 1175);
WIRE 16 -1 (-7075 1225)(-7325 1225);
WIRE 16 -1 (-7325 1275)(-7325 1225);
WIRE 16 -1 (-7075 1275)(-7325 1275);
WIRE 16 -1 (-7325 1325)(-7325 1275);
WIRE 16 -1 (-7075 1325)(-7325 1325);
WIRE 16 -1 (-7325 1375)(-7325 1325);
WIRE 16 -1 (-7075 1375)(-7325 1375);
WIRE 16 -1 (-7325 1425)(-7325 1375);
WIRE 16 -1 (-7075 1425)(-7325 1425);
WIRE 16 -1 (-7325 1475)(-7325 1425);
WIRE 16 -1 (-7075 1475)(-7325 1475);
WIRE 16 -1 (-7325 1525)(-7325 1475);
WIRE 16 -1 (-7075 1525)(-7325 1525);
WIRE 16 -1 (-7325 1575)(-7325 1525);
WIRE 16 -1 (-7075 1575)(-7325 1575);
WIRE 16 -1 (-7325 1625)(-7325 1575);
WIRE 16 -1 (-7075 1625)(-7325 1625);
WIRE 16 -1 (-7325 1675)(-7325 1625);
WIRE 16 -1 (-7075 1675)(-7325 1675);
WIRE 16 -1 (-7325 1725)(-7325 1675);
WIRE 16 -1 (-7075 1725)(-7325 1725);
WIRE 16 -1 (-7325 1775)(-7325 1725);
WIRE 16 -1 (-7075 1775)(-7325 1775);
WIRE 16 -1 (-7325 1825)(-7325 1775);
WIRE 16 -1 (-7075 1825)(-7325 1825);
WIRE 16 -1 (-7325 1875)(-7325 1825);
WIRE 16 -1 (-7075 1875)(-7325 1875);
WIRE 16 -1 (-7325 1925)(-7325 1875);
WIRE 16 -1 (-7075 1925)(-7325 1925);
WIRE 16 -1 (-7325 1975)(-7325 1925);
WIRE 16 -1 (-7075 1975)(-7325 1975);
WIRE 16 -1 (-7325 2025)(-7325 1975);
WIRE 16 -1 (-7075 2025)(-7325 2025);
WIRE 16 -1 (-7325 2075)(-7325 2025);
WIRE 16 -1 (-7075 2075)(-7325 2075);
WIRE 16 -1 (-7325 2125)(-7325 2075);
WIRE 16 -1 (-7075 2125)(-7325 2125);
WIRE 16 -1 (-7325 2175)(-7325 2125);
WIRE 16 -1 (-7075 2175)(-7325 2175);
WIRE 16 -1 (-7325 2225)(-7325 2175);
WIRE 16 -1 (-7075 2225)(-7325 2225);
WIRE 16 -1 (-7325 2275)(-7325 2225);
WIRE 16 -1 (-7075 2275)(-7325 2275);
WIRE 16 -1 (-7325 2325)(-7325 2275);
WIRE 16 -1 (-7075 2325)(-7325 2325);
WIRE 16 -1 (-7325 2375)(-7325 2325);
WIRE 16 -1 (-7075 2375)(-7325 2375);
WIRE 16 -1 (-7325 2425)(-7325 2375);
WIRE 16 -1 (-7075 2425)(-7325 2425);
WIRE 16 -1 (-7325 2475)(-7325 2425);
WIRE 16 -1 (-7075 2475)(-7325 2475);
WIRE 16 -1 (-7325 2525)(-7325 2475);
WIRE 16 -1 (-7075 2525)(-7325 2525);
WIRE 16 -1 (-7325 2575)(-7325 2525);
WIRE 16 -1 (-7075 2575)(-7325 2575);
WIRE 16 -1 (-7325 2625)(-7325 2575);
WIRE 16 -1 (-7075 2625)(-7325 2625);
WIRE 16 -1 (-7325 2675)(-7325 2625);
WIRE 16 -1 (-7075 2675)(-7325 2675);
WIRE 16 -1 (-7325 2725)(-7325 2675);
WIRE 16 -1 (-7075 2725)(-7325 2725);
WIRE 16 -1 (-7325 2775)(-7325 2725);
WIRE 16 -1 (-7075 2775)(-7325 2775);
WIRE 16 -1 (-7325 2825)(-7325 2775);
WIRE 16 -1 (-7075 2825)(-7325 2825);
WIRE 16 -1 (-7325 2875)(-7325 2825);
WIRE 16 -1 (-7075 2875)(-7325 2875);
WIRE 16 -1 (-7325 2925)(-7325 2875);
WIRE 16 -1 (-7075 2925)(-7325 2925);
WIRE 16 -1 (-7325 2975)(-7325 2925);
WIRE 16 -1 (-7075 2975)(-7325 2975);
WIRE 16 -1 (-7325 3025)(-7325 2975);
WIRE 16 -1 (-7075 3025)(-7325 3025);
WIRE 16 -1 (-7325 3075)(-7325 3025);
WIRE 16 -1 (-7075 3075)(-7325 3075);
WIRE 16 -1 (-7325 3125)(-7325 3075);
WIRE 16 -1 (-7075 3125)(-7325 3125);
WIRE 16 -1 (-7325 3175)(-7325 3125);
WIRE 16 -1 (-7075 3175)(-7325 3175);
WIRE 16 -1 (-7325 3225)(-7325 3175);
WIRE 16 -1 (-7075 3225)(-7325 3225);
WIRE 16 -1 (-7325 3275)(-7325 3225);
WIRE 16 -1 (-7075 3275)(-7325 3275);
WIRE 16 -1 (-7325 3325)(-7325 3275);
WIRE 16 -1 (-7075 3325)(-7325 3325);
WIRE 16 -1 (-7325 3375)(-7325 3325);
WIRE 16 -1 (-7075 3375)(-7325 3375);
WIRE 16 -1 (-7325 3425)(-7325 3375);
WIRE 16 -1 (-7075 3425)(-7325 3425);
WIRE 16 -1 (-7325 3475)(-7325 3425);
WIRE 16 -1 (-7075 3475)(-7325 3475);
WIRE 16 -1 (-7325 3525)(-7325 3475);
WIRE 16 -1 (-7075 3525)(-7325 3525);
WIRE 16 -1 (-7325 3575)(-7325 3525);
WIRE 16 -1 (-7075 3575)(-7325 3575);
WIRE 16 -1 (-7325 3625)(-7325 3575);
WIRE 16 -1 (-7075 3625)(-7325 3625);
WIRE 16 -1 (-7325 3675)(-7325 3625);
WIRE 16 -1 (-7075 3675)(-7325 3675);
WIRE 16 -1 (-7325 3725)(-7325 3675);
WIRE 16 -1 (-7075 3725)(-7325 3725);
WIRE 16 -1 (-7325 3775)(-7325 3725);
WIRE 16 -1 (-7075 3775)(-7325 3775);
WIRE 16 -1 (-7325 3825)(-7325 3775);
WIRE 16 -1 (-7075 3825)(-7325 3825);
WIRE 16 -1 (-7325 3875)(-7325 3825);
WIRE 16 -1 (-7075 3875)(-7325 3875);
WIRE 16 -1 (-7325 3925)(-7325 3875);
WIRE 16 -1 (-7075 3925)(-7325 3925);
WIRE 16 -1 (-7325 3975)(-7325 3925);
WIRE 16 -1 (-7075 3975)(-7325 3975);
WIRE 16 -1 (-7325 4025)(-7325 3975);
WIRE 16 -1 (-7075 4025)(-7325 4025);
WIRE 16 -1 (-7325 4075)(-7325 4025);
WIRE 16 -1 (-7075 4075)(-7325 4075);
WIRE 16 -1 (-7325 4125)(-7325 4075);
WIRE 16 -1 (-7075 4125)(-7325 4125);
WIRE 16 -1 (-7325 4175)(-7325 4125);
WIRE 16 -1 (-7075 4175)(-7325 4175);
WIRE 16 -1 (-7325 4225)(-7325 4175);
WIRE 16 -1 (-7075 4225)(-7325 4225);
WIRE 16 -1 (-7325 4350)(-7325 4225);
WIRE 16 -1 (-3600 825)(-3375 825);
WIRE 16 -1 (-3600 875)(-3600 825);
WIRE 16 -1 (-3600 875)(-3375 875);
WIRE 16 -1 (-3600 925)(-3600 875);
WIRE 16 -1 (-3600 925)(-3375 925);
WIRE 16 -1 (-3600 975)(-3600 925);
WIRE 16 -1 (-3600 1025)(-3600 975);
WIRE 16 -1 (-3600 975)(-3375 975);
WIRE 16 -1 (-3600 1025)(-3375 1025);
WIRE 16 -1 (-3600 1075)(-3600 1025);
WIRE 16 -1 (-3600 1075)(-3375 1075);
WIRE 16 -1 (-3600 1125)(-3600 1075);
WIRE 16 -1 (-3600 1125)(-3375 1125);
WIRE 16 -1 (-3600 1175)(-3600 1125);
WIRE 16 -1 (-3600 1175)(-3375 1175);
WIRE 16 -1 (-3600 1225)(-3600 1175);
WIRE 16 -1 (-3600 1225)(-3375 1225);
WIRE 16 -1 (-3600 1275)(-3600 1225);
WIRE 16 -1 (-3600 1275)(-3375 1275);
WIRE 16 -1 (-3600 1325)(-3600 1275);
WIRE 16 -1 (-3600 1325)(-3375 1325);
WIRE 16 -1 (-3600 1375)(-3600 1325);
WIRE 16 -1 (-3600 1375)(-3375 1375);
WIRE 16 -1 (-3600 1425)(-3600 1375);
WIRE 16 -1 (-3600 1425)(-3375 1425);
WIRE 16 -1 (-3600 1475)(-3600 1425);
WIRE 16 -1 (-3600 1475)(-3375 1475);
WIRE 16 -1 (-3600 1525)(-3600 1475);
WIRE 16 -1 (-3600 1525)(-3375 1525);
WIRE 16 -1 (-3600 1575)(-3600 1525);
WIRE 16 -1 (-3600 1575)(-3375 1575);
WIRE 16 -1 (-3600 1625)(-3600 1575);
WIRE 16 -1 (-3600 1625)(-3375 1625);
WIRE 16 -1 (-3600 1675)(-3600 1625);
WIRE 16 -1 (-3600 1675)(-3375 1675);
WIRE 16 -1 (-3600 1725)(-3600 1675);
WIRE 16 -1 (-3600 1725)(-3375 1725);
WIRE 16 -1 (-3600 1775)(-3600 1725);
WIRE 16 -1 (-3600 1775)(-3375 1775);
WIRE 16 -1 (-3600 1825)(-3600 1775);
WIRE 16 -1 (-3600 1825)(-3375 1825);
WIRE 16 -1 (-3600 1875)(-3600 1825);
WIRE 16 -1 (-3600 1875)(-3375 1875);
WIRE 16 -1 (-3600 1925)(-3600 1875);
WIRE 16 -1 (-3600 1925)(-3375 1925);
WIRE 16 -1 (-3600 1975)(-3600 1925);
WIRE 16 -1 (-3600 1975)(-3375 1975);
WIRE 16 -1 (-3600 2025)(-3600 1975);
WIRE 16 -1 (-3600 2075)(-3600 2025);
WIRE 16 -1 (-3600 2025)(-3375 2025);
WIRE 16 -1 (-3600 2075)(-3375 2075);
WIRE 16 -1 (-3600 2125)(-3600 2075);
WIRE 16 -1 (-3600 2125)(-3375 2125);
WIRE 16 -1 (-3600 2175)(-3600 2125);
WIRE 16 -1 (-3600 2175)(-3375 2175);
WIRE 16 -1 (-3600 2225)(-3600 2175);
WIRE 16 -1 (-3600 2225)(-3375 2225);
WIRE 16 -1 (-3600 2275)(-3600 2225);
WIRE 16 -1 (-3600 2275)(-3375 2275);
WIRE 16 -1 (-3600 2325)(-3600 2275);
WIRE 16 -1 (-3600 2325)(-3375 2325);
WIRE 16 -1 (-3600 2375)(-3600 2325);
WIRE 16 -1 (-3600 2375)(-3375 2375);
WIRE 16 -1 (-3600 2425)(-3600 2375);
WIRE 16 -1 (-3600 2425)(-3375 2425);
WIRE 16 -1 (-3600 2475)(-3600 2425);
WIRE 16 -1 (-3600 2475)(-3375 2475);
WIRE 16 -1 (-3600 2525)(-3600 2475);
WIRE 16 -1 (-3600 2525)(-3375 2525);
WIRE 16 -1 (-3600 2575)(-3600 2525);
WIRE 16 -1 (-3600 2575)(-3375 2575);
WIRE 16 -1 (-3600 2625)(-3600 2575);
WIRE 16 -1 (-3600 2625)(-3375 2625);
WIRE 16 -1 (-3600 2675)(-3600 2625);
WIRE 16 -1 (-3600 2675)(-3375 2675);
WIRE 16 -1 (-3600 2725)(-3600 2675);
WIRE 16 -1 (-3600 2725)(-3375 2725);
WIRE 16 -1 (-3600 2775)(-3600 2725);
WIRE 16 -1 (-3600 2775)(-3375 2775);
WIRE 16 -1 (-3600 2825)(-3600 2775);
WIRE 16 -1 (-3600 2825)(-3375 2825);
WIRE 16 -1 (-3600 2875)(-3600 2825);
WIRE 16 -1 (-3600 2875)(-3375 2875);
WIRE 16 -1 (-3600 2925)(-3600 2875);
WIRE 16 -1 (-3600 2925)(-3375 2925);
WIRE 16 -1 (-3600 2975)(-3600 2925);
WIRE 16 -1 (-3600 2975)(-3375 2975);
WIRE 16 -1 (-3600 3025)(-3600 2975);
WIRE 16 -1 (-3600 3075)(-3600 3025);
WIRE 16 -1 (-3600 3025)(-3375 3025);
WIRE 16 -1 (-3600 3075)(-3375 3075);
WIRE 16 -1 (-3600 3125)(-3600 3075);
WIRE 16 -1 (-3600 3125)(-3375 3125);
WIRE 16 -1 (-3600 3175)(-3600 3125);
WIRE 16 -1 (-3600 3175)(-3375 3175);
WIRE 16 -1 (-3600 3225)(-3600 3175);
WIRE 16 -1 (-3600 3225)(-3375 3225);
WIRE 16 -1 (-3600 3275)(-3600 3225);
WIRE 16 -1 (-3600 3275)(-3375 3275);
WIRE 16 -1 (-3600 3325)(-3600 3275);
WIRE 16 -1 (-3600 3325)(-3375 3325);
WIRE 16 -1 (-3600 3375)(-3600 3325);
WIRE 16 -1 (-3600 3375)(-3375 3375);
WIRE 16 -1 (-3600 3425)(-3600 3375);
WIRE 16 -1 (-3600 3425)(-3375 3425);
WIRE 16 -1 (-3600 3475)(-3600 3425);
WIRE 16 -1 (-3600 3475)(-3375 3475);
WIRE 16 -1 (-3600 3525)(-3600 3475);
WIRE 16 -1 (-3600 3525)(-3375 3525);
WIRE 16 -1 (-3600 3575)(-3600 3525);
WIRE 16 -1 (-3600 3575)(-3375 3575);
WIRE 16 -1 (-3600 3625)(-3600 3575);
WIRE 16 -1 (-3600 3625)(-3375 3625);
WIRE 16 -1 (-3600 3675)(-3600 3625);
WIRE 16 -1 (-3600 3675)(-3375 3675);
WIRE 16 -1 (-3600 3725)(-3600 3675);
WIRE 16 -1 (-3600 3725)(-3375 3725);
WIRE 16 -1 (-3600 3775)(-3600 3725);
WIRE 16 -1 (-3600 3775)(-3375 3775);
WIRE 16 -1 (-3600 3825)(-3600 3775);
WIRE 16 -1 (-3600 3825)(-3375 3825);
WIRE 16 -1 (-3600 3875)(-3600 3825);
WIRE 16 -1 (-3600 3875)(-3375 3875);
WIRE 16 -1 (-3600 3925)(-3600 3875);
WIRE 16 -1 (-3600 3925)(-3375 3925);
WIRE 16 -1 (-3600 3975)(-3600 3925);
WIRE 16 -1 (-3600 3975)(-3375 3975);
WIRE 16 -1 (-3600 4025)(-3600 3975);
WIRE 16 -1 (-3600 4025)(-3375 4025);
WIRE 16 -1 (-3600 4075)(-3600 4025);
WIRE 16 -1 (-3600 4125)(-3600 4075);
WIRE 16 -1 (-3600 4075)(-3375 4075);
WIRE 16 -1 (-3600 4125)(-3375 4125);
WIRE 16 -1 (-3600 4175)(-3600 4125);
WIRE 16 -1 (-3600 4175)(-3375 4175);
WIRE 16 -1 (-3600 4225)(-3600 4175);
WIRE 16 -1 (-3600 4225)(-3375 4225);
WIRE 16 -1 (-3600 4350)(-3600 4225);
WIRE 16 -1 (-1725 1275)(-1725 1225);
WIRE 16 -1 (-1725 1325)(-1725 1275);
WIRE 16 -1 (-1725 1275)(-1975 1275);
WIRE 16 -1 (-1725 1225)(-1975 1225);
WIRE 16 -1 (-1725 1375)(-1725 1325);
WIRE 16 -1 (-1725 1325)(-1975 1325);
WIRE 16 -1 (-1725 1425)(-1725 1375);
WIRE 16 -1 (-1725 1375)(-1975 1375);
WIRE 16 -1 (-1725 1475)(-1725 1425);
WIRE 16 -1 (-1725 1425)(-1975 1425);
WIRE 16 -1 (-1725 1525)(-1725 1475);
WIRE 16 -1 (-1725 1475)(-1975 1475);
WIRE 16 -1 (-1725 1575)(-1725 1525);
WIRE 16 -1 (-1725 1525)(-1975 1525);
WIRE 16 -1 (-1725 1625)(-1725 1575);
WIRE 16 -1 (-1725 1575)(-1975 1575);
WIRE 16 -1 (-1725 1675)(-1725 1625);
WIRE 16 -1 (-1725 1625)(-1975 1625);
WIRE 16 -1 (-1725 1725)(-1725 1675);
WIRE 16 -1 (-1725 1675)(-1975 1675);
WIRE 16 -1 (-1725 1775)(-1725 1725);
WIRE 16 -1 (-1725 1725)(-1975 1725);
WIRE 16 -1 (-1725 1825)(-1725 1775);
WIRE 16 -1 (-1725 1775)(-1975 1775);
WIRE 16 -1 (-1725 1875)(-1725 1825);
WIRE 16 -1 (-1725 1825)(-1975 1825);
WIRE 16 -1 (-1725 1925)(-1725 1875);
WIRE 16 -1 (-1725 1875)(-1975 1875);
WIRE 16 -1 (-1725 1975)(-1725 1925);
WIRE 16 -1 (-1725 1925)(-1975 1925);
WIRE 16 -1 (-1725 2025)(-1725 1975);
WIRE 16 -1 (-1725 1975)(-1975 1975);
WIRE 16 -1 (-1725 2075)(-1725 2025);
WIRE 16 -1 (-1725 2025)(-1975 2025);
WIRE 16 -1 (-1725 2125)(-1725 2075);
WIRE 16 -1 (-1725 2075)(-1975 2075);
WIRE 16 -1 (-1725 2175)(-1725 2125);
WIRE 16 -1 (-1725 2125)(-1975 2125);
WIRE 16 -1 (-1725 2225)(-1725 2175);
WIRE 16 -1 (-1725 2175)(-1975 2175);
WIRE 16 -1 (-1725 2275)(-1725 2225);
WIRE 16 -1 (-1725 2225)(-1975 2225);
WIRE 16 -1 (-1725 2325)(-1725 2275);
WIRE 16 -1 (-1725 2275)(-1975 2275);
WIRE 16 -1 (-1725 2375)(-1725 2325);
WIRE 16 -1 (-1725 2325)(-1975 2325);
WIRE 16 -1 (-1725 2425)(-1725 2375);
WIRE 16 -1 (-1725 2375)(-1975 2375);
WIRE 16 -1 (-1725 2475)(-1725 2425);
WIRE 16 -1 (-1725 2425)(-1975 2425);
WIRE 16 -1 (-1725 2525)(-1725 2475);
WIRE 16 -1 (-1725 2475)(-1975 2475);
WIRE 16 -1 (-1725 2575)(-1725 2525);
WIRE 16 -1 (-1725 2525)(-1975 2525);
WIRE 16 -1 (-1725 2625)(-1725 2575);
WIRE 16 -1 (-1725 2575)(-1975 2575);
WIRE 16 -1 (-1725 2675)(-1725 2625);
WIRE 16 -1 (-1725 2625)(-1975 2625);
WIRE 16 -1 (-1725 2725)(-1725 2675);
WIRE 16 -1 (-1725 2675)(-1975 2675);
WIRE 16 -1 (-1725 2775)(-1725 2725);
WIRE 16 -1 (-1725 2725)(-1975 2725);
WIRE 16 -1 (-1725 2825)(-1725 2775);
WIRE 16 -1 (-1725 2775)(-1975 2775);
WIRE 16 -1 (-1725 2875)(-1725 2825);
WIRE 16 -1 (-1725 2825)(-1975 2825);
WIRE 16 -1 (-1725 2925)(-1725 2875);
WIRE 16 -1 (-1725 2875)(-1975 2875);
WIRE 16 -1 (-1725 2975)(-1725 2925);
WIRE 16 -1 (-1725 2925)(-1975 2925);
WIRE 16 -1 (-1725 3025)(-1725 2975);
WIRE 16 -1 (-1725 2975)(-1975 2975);
WIRE 16 -1 (-1725 3075)(-1725 3025);
WIRE 16 -1 (-1725 3025)(-1975 3025);
WIRE 16 -1 (-1725 3125)(-1725 3075);
WIRE 16 -1 (-1725 3075)(-1975 3075);
WIRE 16 -1 (-1725 3175)(-1725 3125);
WIRE 16 -1 (-1725 3125)(-1975 3125);
WIRE 16 -1 (-1725 3225)(-1725 3175);
WIRE 16 -1 (-1725 3175)(-1975 3175);
WIRE 16 -1 (-1725 3275)(-1725 3225);
WIRE 16 -1 (-1725 3225)(-1975 3225);
WIRE 16 -1 (-1725 3325)(-1725 3275);
WIRE 16 -1 (-1725 3275)(-1975 3275);
WIRE 16 -1 (-1725 3375)(-1725 3325);
WIRE 16 -1 (-1725 3325)(-1975 3325);
WIRE 16 -1 (-1725 3425)(-1725 3375);
WIRE 16 -1 (-1725 3375)(-1975 3375);
WIRE 16 -1 (-1725 3475)(-1725 3425);
WIRE 16 -1 (-1725 3425)(-1975 3425);
WIRE 16 -1 (-1725 3525)(-1725 3475);
WIRE 16 -1 (-1725 3475)(-1975 3475);
WIRE 16 -1 (-1725 3575)(-1725 3525);
WIRE 16 -1 (-1725 3525)(-1975 3525);
WIRE 16 -1 (-1725 3625)(-1725 3575);
WIRE 16 -1 (-1725 3575)(-1975 3575);
WIRE 16 -1 (-1725 3675)(-1725 3625);
WIRE 16 -1 (-1725 3625)(-1975 3625);
WIRE 16 -1 (-1725 3725)(-1725 3675);
WIRE 16 -1 (-1725 3675)(-1975 3675);
WIRE 16 -1 (-1725 3775)(-1725 3725);
WIRE 16 -1 (-1725 3725)(-1975 3725);
WIRE 16 -1 (-1725 3825)(-1725 3775);
WIRE 16 -1 (-1725 3775)(-1975 3775);
WIRE 16 -1 (-1725 3875)(-1725 3825);
WIRE 16 -1 (-1725 3825)(-1975 3825);
WIRE 16 -1 (-1725 3925)(-1725 3875);
WIRE 16 -1 (-1725 3875)(-1975 3875);
WIRE 16 -1 (-1725 3975)(-1725 3925);
WIRE 16 -1 (-1725 3925)(-1975 3925);
WIRE 16 -1 (-1725 4025)(-1725 3975);
WIRE 16 -1 (-1725 3975)(-1975 3975);
WIRE 16 -1 (-1725 4075)(-1725 4025);
WIRE 16 -1 (-1725 4025)(-1975 4025);
WIRE 16 -1 (-1725 4125)(-1725 4075);
WIRE 16 -1 (-1725 4075)(-1975 4075);
WIRE 16 -1 (-1725 4175)(-1725 4125);
WIRE 16 -1 (-1725 4125)(-1975 4125);
WIRE 16 -1 (-1725 4225)(-1725 4175);
WIRE 16 -1 (-1725 4175)(-1975 4175);
WIRE 16 -1 (-1725 4325)(-1725 4225);
WIRE 16 -1 (-1725 4225)(-1975 4225);
WIRE 16 -1 (-500 650)(-500 575);
WIRE 16 -1 (-1100 1500)(-1100 1650);
WIRE 16 -1 (-500 1300)(-500 1450);
WIRE 16 -1 (-500 925)(-500 1100);
WIRE 16 -1 (-500 850)(-500 925);
WIRE 16 -1 (-500 925)(-1975 925);
FORCEPROP 0 LAST SIG_NAME VSENSE_PMAX_CPU1
J 0
(-1775 935);
DISPLAY 0.617021 (-1775 935);
PAINT ORANGE (-1775 935);
FORCEPROP 2 LASTPROP $XRERR UNIQUE?
J 0
(-2015 935);
DISPLAY 0.638298 (-2015 935);
PAINT MONO (-2015 935);
DISPLAY INVISIBLE (-2015 935);
WIRE 16 -1 (-925 825)(-1975 825);
FORCEPROP 0 LAST SIG_NAME VSENSE_PVCCIN_CPU1_SKT_VSEN
J 0
(-1775 834);
DISPLAY 0.617021 (-1775 834);
PAINT ORANGE (-1775 834);
WIRE 16 -1 (-925 775)(-1975 775);
FORCEPROP 0 LAST SIG_NAME VSENSE_PVCCIN_CPU1_SKT_VRTN
J 0
(-1775 775);
DISPLAY 0.617021 (-1775 775);
PAINT ORANGE (-1775 775);
WIRE 16 -1 (-1100 1125)(-1100 1300);
WIRE 16 -1 (-1100 1125)(-1100 1025);
WIRE 16 -1 (-1100 1125)(-1975 1125);
FORCEPROP 0 LAST SIG_NAME VSENSE_VCCINR2PMAX_CPU1
J 0
(-1775 1135);
DISPLAY 0.617021 (-1775 1135);
PAINT ORANGE (-1775 1135);
FORCEPROP 2 LASTPROP $XRERR UNIQUE?
J 0
(-2015 1135);
DISPLAY 0.638298 (-2015 1135);
PAINT MONO (-2015 1135);
DISPLAY INVISIBLE (-2015 1135);
WIRE 16 -1 (-1100 1025)(-1975 1025);
DOT 1 (-1725 4225);
DOT 1 (-1725 4175);
DOT 1 (-1725 4125);
DOT 1 (-3600 4225);
DOT 1 (-3600 4125);
DOT 1 (-3600 4175);
DOT 1 (-1725 4025);
DOT 1 (-1725 4075);
DOT 1 (-1725 3975);
DOT 1 (-1725 3925);
DOT 1 (-1725 3875);
DOT 1 (-1725 3775);
DOT 1 (-1725 3825);
DOT 1 (-1725 3725);
DOT 1 (-1725 3675);
DOT 1 (-1725 3625);
DOT 1 (-1725 3475);
DOT 1 (-1725 3575);
DOT 1 (-1725 3525);
DOT 1 (-1725 3375);
DOT 1 (-1725 3425);
DOT 1 (-1725 3275);
DOT 1 (-1725 3325);
DOT 1 (-1725 3225);
DOT 1 (-1725 3175);
DOT 1 (-1725 3125);
DOT 1 (-1725 3075);
DOT 1 (-1725 3025);
DOT 1 (-1725 2975);
DOT 1 (-1725 2875);
DOT 1 (-1725 2925);
DOT 1 (-1725 2825);
DOT 1 (-1725 2725);
DOT 1 (-1725 2775);
DOT 1 (-1725 2675);
DOT 1 (-1725 2575);
DOT 1 (-1725 2625);
DOT 1 (-1725 2475);
DOT 1 (-1725 2525);
DOT 1 (-1725 2425);
DOT 1 (-1725 2375);
DOT 1 (-1725 2325);
DOT 1 (-1725 2225);
DOT 1 (-1725 2275);
DOT 1 (-1725 2175);
DOT 1 (-1725 2075);
DOT 1 (-1725 2125);
DOT 1 (-500 925);
DOT 1 (-1100 1125);
DOT 1 (-1725 1975);
DOT 1 (-1725 2025);
DOT 1 (-1725 1925);
DOT 1 (-1725 1875);
DOT 1 (-1725 1825);
DOT 1 (-1725 1775);
DOT 1 (-1725 1725);
DOT 1 (-1725 1675);
DOT 1 (-1725 1575);
DOT 1 (-1725 1625);
DOT 1 (-1725 1525);
DOT 1 (-1725 1475);
DOT 1 (-1725 1425);
DOT 1 (-1725 1325);
DOT 1 (-1725 1375);
DOT 1 (-1725 1275);
DOT 1 (-3600 4075);
DOT 1 (-3600 4025);
DOT 1 (-3600 3975);
DOT 1 (-3600 3875);
DOT 1 (-3600 3925);
DOT 1 (-3600 3825);
DOT 1 (-3600 3775);
DOT 1 (-3600 3725);
DOT 1 (-3600 3625);
DOT 1 (-3600 3675);
DOT 1 (-3600 3575);
DOT 1 (-3600 3525);
DOT 1 (-3600 3475);
DOT 1 (-3600 3375);
DOT 1 (-3600 3425);
DOT 1 (-3600 3325);
DOT 1 (-3600 3275);
DOT 1 (-3600 3225);
DOT 1 (-3600 3175);
DOT 1 (-3600 3125);
DOT 1 (-3600 3075);
DOT 1 (-3600 2975);
DOT 1 (-3600 3025);
DOT 1 (-3600 2925);
DOT 1 (-3600 2875);
DOT 1 (-3600 2825);
DOT 1 (-3600 2775);
DOT 1 (-3600 2725);
DOT 1 (-3600 2675);
DOT 1 (-3600 2625);
DOT 1 (-3600 2575);
DOT 1 (-3600 2475);
DOT 1 (-3600 2525);
DOT 1 (-3600 2425);
DOT 1 (-3600 2375);
DOT 1 (-3600 2325);
DOT 1 (-3600 2225);
DOT 1 (-3600 2275);
DOT 1 (-3600 2175);
DOT 1 (-3600 2125);
DOT 1 (-3600 2075);
DOT 1 (-3600 2025);
DOT 1 (-3600 1975);
DOT 1 (-3600 1925);
DOT 1 (-3600 1825);
DOT 1 (-3600 1875);
DOT 1 (-3600 1775);
DOT 1 (-3600 1725);
DOT 1 (-3600 1675);
DOT 1 (-3600 1575);
DOT 1 (-3600 1625);
DOT 1 (-3600 1525);
DOT 1 (-3600 1475);
DOT 1 (-3600 1425);
DOT 1 (-3600 1325);
DOT 1 (-3600 1375);
DOT 1 (-3600 1275);
DOT 1 (-3600 1225);
DOT 1 (-3600 1175);
DOT 1 (-3600 1125);
DOT 1 (-3600 1075);
DOT 1 (-3600 1025);
DOT 1 (-3600 975);
DOT 1 (-3600 925);
DOT 1 (-3600 875);
DOT 1 (-5425 4225);
DOT 1 (-5425 4125);
DOT 1 (-5425 4175);
DOT 1 (-7325 4225);
DOT 1 (-7325 4125);
DOT 1 (-7325 4175);
DOT 1 (-5425 4075);
DOT 1 (-5425 4025);
DOT 1 (-5425 3975);
DOT 1 (-5425 3875);
DOT 1 (-5425 3925);
DOT 1 (-5425 3825);
DOT 1 (-5425 3775);
DOT 1 (-5425 3725);
DOT 1 (-5425 3625);
DOT 1 (-5425 3675);
DOT 1 (-5425 3575);
DOT 1 (-5425 3525);
DOT 1 (-5425 3475);
DOT 1 (-5425 3375);
DOT 1 (-5425 3425);
DOT 1 (-5425 3325);
DOT 1 (-5425 3275);
DOT 1 (-5425 3225);
DOT 1 (-5425 3175);
DOT 1 (-5425 3125);
DOT 1 (-5425 3075);
DOT 1 (-5425 2975);
DOT 1 (-5425 3025);
DOT 1 (-5425 2925);
DOT 1 (-5425 2875);
DOT 1 (-5425 2825);
DOT 1 (-5425 2725);
DOT 1 (-5425 2775);
DOT 1 (-5425 2675);
DOT 1 (-5425 2625);
DOT 1 (-5425 2575);
DOT 1 (-5425 2475);
DOT 1 (-5425 2525);
DOT 1 (-5425 2425);
DOT 1 (-5425 2375);
DOT 1 (-5425 2325);
DOT 1 (-5425 2225);
DOT 1 (-5425 2275);
DOT 1 (-5425 2175);
DOT 1 (-5425 2125);
DOT 1 (-5425 2075);
DOT 1 (-5425 2025);
DOT 1 (-5425 1975);
DOT 1 (-5425 1925);
DOT 1 (-5425 1825);
DOT 1 (-5425 1875);
DOT 1 (-5425 1775);
DOT 1 (-5425 1725);
DOT 1 (-5425 1675);
DOT 1 (-5425 1575);
DOT 1 (-5425 1625);
DOT 1 (-5425 1525);
DOT 1 (-5425 1475);
DOT 1 (-5425 1425);
DOT 1 (-5425 1325);
DOT 1 (-5425 1375);
DOT 1 (-5425 1275);
DOT 1 (-5425 1225);
DOT 1 (-5425 1175);
DOT 1 (-5425 1125);
DOT 1 (-5425 1075);
DOT 1 (-5425 1025);
DOT 1 (-5425 975);
DOT 1 (-5425 925);
DOT 1 (-5425 875);
DOT 1 (-7325 4075);
DOT 1 (-7325 4025);
DOT 1 (-7325 3975);
DOT 1 (-7325 3875);
DOT 1 (-7325 3925);
DOT 1 (-7325 3825);
DOT 1 (-7325 3775);
DOT 1 (-7325 3725);
DOT 1 (-7325 3625);
DOT 1 (-7325 3675);
DOT 1 (-7325 3575);
DOT 1 (-7325 3525);
DOT 1 (-7325 3475);
DOT 1 (-7325 3375);
DOT 1 (-7325 3425);
DOT 1 (-7325 3325);
DOT 1 (-7325 3275);
DOT 1 (-7325 3225);
DOT 1 (-7325 3175);
DOT 1 (-7325 3125);
DOT 1 (-7325 3075);
DOT 1 (-7325 2975);
DOT 1 (-7325 3025);
DOT 1 (-7325 2925);
DOT 1 (-7325 2875);
DOT 1 (-7325 2825);
DOT 1 (-7325 2725);
DOT 1 (-7325 2775);
DOT 1 (-7325 2675);
DOT 1 (-7325 2625);
DOT 1 (-7325 2575);
DOT 1 (-7325 2475);
DOT 1 (-7325 2525);
DOT 1 (-7325 2425);
DOT 1 (-7325 2375);
DOT 1 (-7325 2325);
DOT 1 (-7325 2225);
DOT 1 (-7325 2275);
DOT 1 (-7325 2175);
DOT 1 (-7325 2125);
DOT 1 (-7325 2075);
DOT 1 (-7325 2025);
DOT 1 (-7325 1975);
DOT 1 (-7325 1925);
DOT 1 (-7325 1825);
DOT 1 (-7325 1875);
DOT 1 (-7325 1775);
DOT 1 (-7325 1725);
DOT 1 (-7325 1675);
DOT 1 (-7325 1575);
DOT 1 (-7325 1625);
DOT 1 (-7325 1525);
DOT 1 (-7325 1475);
DOT 1 (-7325 1425);
DOT 1 (-7325 1325);
DOT 1 (-7325 1375);
DOT 1 (-7325 1275);
DOT 1 (-7325 1225);
DOT 1 (-7325 1175);
DOT 1 (-7325 1125);
DOT 1 (-7325 1075);
DOT 1 (-7325 1025);
DOT 1 (-7325 925);
DOT 1 (-7325 975);
DOT 1 (-7325 875);
FORCENOTE
BOM_COST=PROC_SOCKET
(-7950 175) 0;
DISPLAY LEFT (-7950 175);
DISPLAY 1.723404 (-7950 175);
PAINT PURPLE (-7950 175);
FORCENOTE
ROOM=CPU1
(-7950 300) 0;
DISPLAY LEFT (-7950 300);
DISPLAY 1.723404 (-7950 300);
PAINT PURPLE (-7950 300);
QUIT
